FILE_TYPE = MACRO_DRAWING;
SET COLOR_WIRE YELLOW;
SET COLOR_PROP MONO;
SET COLOR_DOT WHITE;
SET COLOR_ARC YELLOW;
SET COLOR_BODY GREEN;
SET COLOR_NOTE MONO;
SET PROP_DISPLAY VALUE;
SET PAGE_NUMBER P114;
FORCEADD OFFPAGE..2
(3700 2250);
FORCEPROP 2 LAST $XR0 108 
J 0
(3889 2250);
DISPLAY 0.638298 (3889 2250);
PAINT MONO (3889 2250);
FORCEPROP 2 LAST PATH I103
J 0
(3875 2325);
DISPLAY 1.021277 (3875 2325);
PAINT ORANGE (3875 2325);
DISPLAY INVISIBLE (3875 2325);
FORCEPROP 2 LAST CDS_LIB mstr_standard
J 0
(3700 2250);
PAINT ORANGE (3700 2250);
DISPLAY INVISIBLE (3700 2250);
FORCEPROP 1 LAST OFFPAGE TRUE
J 0
(4025 2125);
DISPLAY 0.872340 (4025 2125);
PAINT GREEN (4025 2125);
DISPLAY INVISIBLE (4025 2125);
FORCEPROP 1 LAST COMMENT_BODY TRUE
J 0
(3655 2155);
DISPLAY 0.872340 (3655 2155);
PAINT PEACH (3655 2155);
DISPLAY INVISIBLE (3655 2155);
FORCEADD OFFPAGE..2
(3700 2200);
FORCEPROP 2 LAST $XR0 108 
J 0
(3889 2200);
DISPLAY 0.638298 (3889 2200);
PAINT MONO (3889 2200);
FORCEPROP 2 LAST PATH I104
J 0
(3875 2275);
DISPLAY 1.021277 (3875 2275);
PAINT ORANGE (3875 2275);
DISPLAY INVISIBLE (3875 2275);
FORCEPROP 2 LAST CDS_LIB mstr_standard
J 0
(3700 2200);
PAINT ORANGE (3700 2200);
DISPLAY INVISIBLE (3700 2200);
FORCEPROP 1 LAST OFFPAGE TRUE
J 0
(4025 2075);
DISPLAY 0.872340 (4025 2075);
PAINT GREEN (4025 2075);
DISPLAY INVISIBLE (4025 2075);
FORCEPROP 1 LAST COMMENT_BODY TRUE
J 0
(3655 2105);
DISPLAY 0.872340 (3655 2105);
PAINT PEACH (3655 2105);
DISPLAY INVISIBLE (3655 2105);
FORCEADD RES..1
(2300 1350);
FORCEPROP 1 LAST PACK_TYPE 0402
J 0
(2500 1300);
DISPLAY 0.617021 (2500 1300);
PAINT SKYBLUE (2500 1300);
FORCEPROP 1 LASTPIN (2400 1350) $PN 2
J 0
(2362 1362);
DISPLAY 0.617021 (2362 1362);
PAINT ORANGE (2362 1362);
FORCEPROP 1 LAST MATERIAL CHIP
J 0
(2375 1300);
DISPLAY 0.617021 (2375 1300);
PAINT SKYBLUE (2375 1300);
FORCEPROP 1 LAST TOLERANCE 1%
J 0
(2300 1300);
DISPLAY 0.617021 (2300 1300);
PAINT SKYBLUE (2300 1300);
FORCEPROP 1 LAST VALUE 10.0
J 2
(2200 1350);
DISPLAY 0.617021 (2200 1350);
PAINT SKYBLUE (2200 1350);
FORCEPROP 1 LASTPIN (2200 1350) $PN 1
J 0
(2212 1362);
DISPLAY 0.617021 (2212 1362);
PAINT ORANGE (2212 1362);
FORCEPROP 1 LAST LOCATION R8B20
J 0
(2250 1400);
DISPLAY 0.617021 (2250 1400);
PAINT AQUA (2250 1400);
FORCEPROP 1 LAST WATTAGE 1/16W
J 2
(2175 1300);
DISPLAY 0.617021 (2175 1300);
PAINT SKYBLUE (2175 1300);
FORCEPROP 1 LAST PART_NUMBER G21796-066
J 0
(2150 1250);
DISPLAY 0.617021 (2150 1250);
PAINT BLUE (2150 1250);
FORCEPROP 2 LAST SEC 1
J 0
(2250 1550);
DISPLAY 0.680851 (2250 1550);
PAINT MONO (2250 1550);
DISPLAY INVISIBLE (2250 1550);
FORCEPROP 2 LAST SEC_TYPE 0402
J 0
(2250 1550);
DISPLAY 1.021277 (2250 1550);
PAINT ORANGE (2250 1550);
DISPLAY INVISIBLE (2250 1550);
FORCEPROP 2 LAST ROOM SB
J 0
(2250 1500);
DISPLAY 1.021277 (2250 1500);
PAINT ORANGE (2250 1500);
DISPLAY INVISIBLE (2250 1500);
FORCEPROP 1 LAST PATH I110
J 0
(2250 1500);
DISPLAY 0.978723 (2250 1500);
PAINT WHITE (2250 1500);
DISPLAY INVISIBLE (2250 1500);
FORCEPROP 2 LAST CDS_LOCATION R8B20
J 0
(2250 1400);
DISPLAY 0.617021 (2250 1400);
PAINT AQUA (2250 1400);
DISPLAY INVISIBLE (2250 1400);
FORCEPROP 2 LAST CDS_LIB mstr_discrete
J 0
(2300 1350);
PAINT ORANGE (2300 1350);
DISPLAY INVISIBLE (2300 1350);
FORCEADD RES..2
(2900 1100);
FORCEPROP 1 LAST LOCATION R8B21
J 0
(2945 1225);
DISPLAY 0.617021 (2945 1225);
PAINT AQUA (2945 1225);
FORCEPROP 1 LAST TOLERANCE 1%
J 0
(2945 1125);
DISPLAY 0.617021 (2945 1125);
PAINT SKYBLUE (2945 1125);
FORCEPROP 1 LAST PACK_TYPE 0402
J 0
(2940 925);
DISPLAY 0.617021 (2940 925);
PAINT SKYBLUE (2940 925);
FORCEPROP 1 LAST PART_NUMBER G21796-047
J 0
(2940 975);
DISPLAY 0.617021 (2940 975);
PAINT BLUE (2940 975);
FORCEPROP 1 LASTPIN (2900 1200) $PN 1
J 0
(2905 1162);
DISPLAY 0.617021 (2905 1162);
PAINT ORANGE (2905 1162);
FORCEPROP 1 LAST VALUE 49.9
J 0
(2945 1175);
DISPLAY 0.617021 (2945 1175);
PAINT SKYBLUE (2945 1175);
FORCEPROP 1 LAST WATTAGE 1/16W
J 0
(2940 1075);
DISPLAY 0.617021 (2940 1075);
PAINT SKYBLUE (2940 1075);
FORCEPROP 1 LAST MATERIAL EMPTY
J 0
(2940 1025);
DISPLAY 0.617021 (2940 1025);
PAINT RED (2940 1025);
FORCEPROP 1 LASTPIN (2900 1000) $PN 2
J 0
(2905 1010);
DISPLAY 0.617021 (2905 1010);
PAINT ORANGE (2905 1010);
FORCEPROP 2 LAST SEC_TYPE 0402
J 0
(2950 1325);
DISPLAY 1.021277 (2950 1325);
PAINT ORANGE (2950 1325);
DISPLAY INVISIBLE (2950 1325);
FORCEPROP 2 LAST SEC 1
J 0
(2950 1325);
DISPLAY 0.680851 (2950 1325);
PAINT MONO (2950 1325);
DISPLAY INVISIBLE (2950 1325);
FORCEPROP 0 LAST ROOM SB
J 0
(2850 1300);
DISPLAY 1.021277 (2850 1300);
PAINT ORANGE (2850 1300);
DISPLAY INVISIBLE (2850 1300);
FORCEPROP 1 LAST PATH I124
J 0
(2950 1275);
DISPLAY 0.978723 (2950 1275);
PAINT WHITE (2950 1275);
DISPLAY INVISIBLE (2950 1275);
FORCEPROP 2 LAST CDS_LOCATION R8B21
J 0
(2945 1225);
DISPLAY 0.617021 (2945 1225);
PAINT AQUA (2945 1225);
DISPLAY INVISIBLE (2945 1225);
FORCEPROP 2 LAST CDS_LIB mstr_discrete
J 0
(2900 1100);
PAINT ORANGE (2900 1100);
DISPLAY INVISIBLE (2900 1100);
FORCEADD GND..1
(2900 850);
FORCEPROP 3 LASTPIN (2900 900) SIG_NAME GND\g
J 0
(2910 910);
DISPLAY 0.659574 (2910 910);
PAINT MONO (2910 910);
DISPLAY INVISIBLE (2910 910);
FORCEPROP 1 LAST SIZE 1B
J 0
(2975 800);
DISPLAY 0.872340 (2975 800);
PAINT AQUA (2975 800);
DISPLAY INVISIBLE (2975 800);
FORCEPROP 1 LAST PATH I125
J 0
(2975 850);
DISPLAY 0.872340 (2975 850);
PAINT AQUA (2975 850);
DISPLAY INVISIBLE (2975 850);
FORCEPROP 1 LAST VOLTAGE 0.0V
J 0
(2855 807);
DISPLAY 0.340426 (2855 807);
PAINT SKYBLUE (2855 807);
DISPLAY INVISIBLE (2855 807);
FORCEPROP 2 LAST CDS_LIB mstr_symbols
J 0
(2900 850);
PAINT ORANGE (2900 850);
DISPLAY INVISIBLE (2900 850);
FORCEPROP 1 LAST BODY_TYPE PLUMBING
J 0
(2855 807);
DISPLAY 0.340426 (2855 807);
PAINT GREEN (2855 807);
DISPLAY INVISIBLE (2855 807);
FORCEPROP 1 LAST HDL_POWER GND
J 0
(2900 1000);
DISPLAY 0.872340 (2900 1000);
PAINT GREEN (2900 1000);
DISPLAY INVISIBLE (2900 1000);
FORCEADD OFFPAGE..2
(3700 1950);
FORCEPROP 2 LAST $XR0 108 
J 0
(3889 1950);
DISPLAY 0.638298 (3889 1950);
PAINT MONO (3889 1950);
FORCEPROP 2 LAST PATH I128
J 0
(3875 2025);
DISPLAY 1.021277 (3875 2025);
PAINT ORANGE (3875 2025);
DISPLAY INVISIBLE (3875 2025);
FORCEPROP 2 LAST CDS_LIB mstr_standard
J 0
(3700 1950);
PAINT ORANGE (3700 1950);
DISPLAY INVISIBLE (3700 1950);
FORCEPROP 1 LAST OFFPAGE TRUE
J 0
(4025 1825);
DISPLAY 0.872340 (4025 1825);
PAINT GREEN (4025 1825);
DISPLAY INVISIBLE (4025 1825);
FORCEPROP 1 LAST COMMENT_BODY TRUE
J 0
(3655 1855);
DISPLAY 0.872340 (3655 1855);
PAINT GREEN (3655 1855);
DISPLAY INVISIBLE (3655 1855);
FORCEADD OFFPAGE..2
(3700 1900);
FORCEPROP 2 LAST $XR0 108 
J 0
(3889 1900);
DISPLAY 0.638298 (3889 1900);
PAINT MONO (3889 1900);
FORCEPROP 2 LAST PATH I129
J 0
(3875 1975);
DISPLAY 1.021277 (3875 1975);
PAINT ORANGE (3875 1975);
DISPLAY INVISIBLE (3875 1975);
FORCEPROP 2 LAST CDS_LIB mstr_standard
J 0
(3700 1900);
PAINT ORANGE (3700 1900);
DISPLAY INVISIBLE (3700 1900);
FORCEPROP 1 LAST OFFPAGE TRUE
J 0
(4025 1775);
DISPLAY 0.872340 (4025 1775);
PAINT GREEN (4025 1775);
DISPLAY INVISIBLE (4025 1775);
FORCEPROP 1 LAST COMMENT_BODY TRUE
J 0
(3655 1805);
DISPLAY 0.872340 (3655 1805);
PAINT GREEN (3655 1805);
DISPLAY INVISIBLE (3655 1805);
FORCEADD OFFPAGE..1
(-2350 2300);
FORCEPROP 2 LAST $XR0 114 
J 0
(-2602 2300);
DISPLAY 0.638298 (-2602 2300);
PAINT MONO (-2602 2300);
FORCEPROP 2 LAST CDS_LIB mstr_standard
J 0
(-2350 2300);
PAINT ORANGE (-2350 2300);
DISPLAY INVISIBLE (-2350 2300);
FORCEPROP 2 LAST PATH I130
J 0
(-2625 2350);
DISPLAY 1.021277 (-2625 2350);
PAINT ORANGE (-2625 2350);
DISPLAY INVISIBLE (-2625 2350);
FORCEPROP 1 LAST OFFPAGE TRUE
J 0
(-2025 2175);
DISPLAY 0.872340 (-2025 2175);
PAINT GREEN (-2025 2175);
DISPLAY INVISIBLE (-2025 2175);
FORCEPROP 1 LAST COMMENT_BODY TRUE
J 0
(-2225 2200);
DISPLAY 0.872340 (-2225 2200);
PAINT PEACH (-2225 2200);
DISPLAY INVISIBLE (-2225 2200);
FORCEADD OFFPAGE..2
R 2
(-2350 2450);
FORCEPROP 2 LAST $XR0 111 
J 0
(-2605 2450);
DISPLAY 0.638298 (-2605 2450);
PAINT MONO (-2605 2450);
FORCEPROP 2 LAST CDS_LIB mstr_standard
J 0
(-2350 2450);
PAINT ORANGE (-2350 2450);
DISPLAY INVISIBLE (-2350 2450);
FORCEPROP 2 LAST PATH I133
J 0
(-2600 2500);
DISPLAY 1.021277 (-2600 2500);
PAINT ORANGE (-2600 2500);
DISPLAY INVISIBLE (-2600 2500);
FORCEPROP 1 LAST OFFPAGE TRUE
J 2
(-2675 2325);
DISPLAY 0.872340 (-2675 2325);
PAINT GREEN (-2675 2325);
DISPLAY INVISIBLE (-2675 2325);
FORCEPROP 1 LAST COMMENT_BODY TRUE
J 2
(-2305 2355);
DISPLAY 0.872340 (-2305 2355);
PAINT PEACH (-2305 2355);
DISPLAY INVISIBLE (-2305 2355);
FORCEADD OFFPAGE..2
R 2
(-2350 2400);
FORCEPROP 2 LAST $XR0 111 
J 0
(-2605 2400);
DISPLAY 0.638298 (-2605 2400);
PAINT MONO (-2605 2400);
FORCEPROP 2 LAST CDS_LIB mstr_standard
J 0
(-2350 2400);
PAINT ORANGE (-2350 2400);
DISPLAY INVISIBLE (-2350 2400);
FORCEPROP 2 LAST PATH I138
J 0
(-2600 2450);
DISPLAY 1.021277 (-2600 2450);
PAINT ORANGE (-2600 2450);
DISPLAY INVISIBLE (-2600 2450);
FORCEPROP 1 LAST OFFPAGE TRUE
J 2
(-2675 2275);
DISPLAY 0.872340 (-2675 2275);
PAINT GREEN (-2675 2275);
DISPLAY INVISIBLE (-2675 2275);
FORCEPROP 1 LAST COMMENT_BODY TRUE
J 2
(-2305 2305);
DISPLAY 0.872340 (-2305 2305);
PAINT PEACH (-2305 2305);
DISPLAY INVISIBLE (-2305 2305);
FORCEADD OFFPAGE..5
(-2350 2850);
FORCEPROP 2 LAST $XR0 145 
J 0
(-2605 2850);
DISPLAY 0.638298 (-2605 2850);
PAINT MONO (-2605 2850);
FORCEPROP 2 LAST PATH I143
J 0
(-2300 2925);
DISPLAY 1.021277 (-2300 2925);
PAINT ORANGE (-2300 2925);
DISPLAY INVISIBLE (-2300 2925);
FORCEPROP 2 LAST CDS_LIB mstr_standard
J 0
(-2350 2850);
PAINT ORANGE (-2350 2850);
DISPLAY INVISIBLE (-2350 2850);
FORCEPROP 1 LAST OFFPAGE TRUE
J 0
(-2025 2725);
DISPLAY 0.872340 (-2025 2725);
PAINT GREEN (-2025 2725);
DISPLAY INVISIBLE (-2025 2725);
FORCEPROP 1 LAST COMMENT_BODY TRUE
J 0
(-2250 2775);
DISPLAY 0.872340 (-2250 2775);
PAINT GREEN (-2250 2775);
DISPLAY INVISIBLE (-2250 2775);
FORCEADD RES..2
(-3150 2750);
FORCEPROP 1 LAST MATERIAL CHIP
J 0
(-3110 2675);
DISPLAY 0.617021 (-3110 2675);
PAINT SKYBLUE (-3110 2675);
FORCEPROP 1 LASTPIN (-3150 2850) $PN 1
J 0
(-3145 2812);
DISPLAY 0.787234 (-3145 2812);
PAINT ORANGE (-3145 2812);
FORCEPROP 1 LASTPIN (-3150 2650) $PN 2
J 0
(-3145 2660);
DISPLAY 0.787234 (-3145 2660);
PAINT ORANGE (-3145 2660);
FORCEPROP 1 LAST WATTAGE 1/16W
J 0
(-3110 2725);
DISPLAY 0.617021 (-3110 2725);
PAINT SKYBLUE (-3110 2725);
FORCEPROP 1 LAST TOLERANCE 1.0%
J 0
(-3105 2775);
DISPLAY 0.617021 (-3105 2775);
PAINT SKYBLUE (-3105 2775);
FORCEPROP 1 LAST VALUE 169
J 0
(-3105 2825);
DISPLAY 0.617021 (-3105 2825);
PAINT SKYBLUE (-3105 2825);
FORCEPROP 1 LAST PACK_TYPE 0402
J 0
(-3110 2575);
DISPLAY 0.617021 (-3110 2575);
PAINT SKYBLUE (-3110 2575);
FORCEPROP 1 LAST PART_NUMBER G21796-276
J 0
(-3110 2625);
DISPLAY 0.617021 (-3110 2625);
PAINT BLUE (-3110 2625);
FORCEPROP 1 LAST LOCATION R3N1
J 0
(-3105 2875);
DISPLAY 0.617021 (-3105 2875);
PAINT AQUA (-3105 2875);
FORCEPROP 2 LAST CDS_LIB mstr_discrete
J 0
(-3150 2750);
PAINT ORANGE (-3150 2750);
DISPLAY INVISIBLE (-3150 2750);
FORCEPROP 0 LAST ROOM SB
J 0
(-3100 2975);
DISPLAY 1.021277 (-3100 2975);
PAINT ORANGE (-3100 2975);
DISPLAY INVISIBLE (-3100 2975);
FORCEPROP 1 LAST PATH I149
J 0
(-3100 2925);
DISPLAY 0.978723 (-3100 2925);
PAINT WHITE (-3100 2925);
DISPLAY INVISIBLE (-3100 2925);
FORCEPROP 2 LAST CDS_LOCATION R3N1
J 0
(-3105 2875);
DISPLAY 0.617021 (-3105 2875);
PAINT AQUA (-3105 2875);
DISPLAY INVISIBLE (-3105 2875);
FORCEPROP 2 LAST SEC 1
J 0
(-3100 2975);
DISPLAY 0.680851 (-3100 2975);
PAINT MONO (-3100 2975);
DISPLAY INVISIBLE (-3100 2975);
FORCEPROP 2 LAST SEC_TYPE 0402
J 0
(-3100 2975);
DISPLAY 1.021277 (-3100 2975);
PAINT ORANGE (-3100 2975);
DISPLAY INVISIBLE (-3100 2975);
FORCEADD GND..1
(-3150 2500);
FORCEPROP 3 LASTPIN (-3150 2550) SIG_NAME GND\g
J 0
(-3140 2560);
DISPLAY 0.659574 (-3140 2560);
PAINT MONO (-3140 2560);
DISPLAY INVISIBLE (-3140 2560);
FORCEPROP 1 LAST PATH I150
J 0
(-3075 2500);
DISPLAY 0.872340 (-3075 2500);
PAINT AQUA (-3075 2500);
DISPLAY INVISIBLE (-3075 2500);
FORCEPROP 1 LAST SIZE 1B
J 0
(-3075 2450);
DISPLAY 0.872340 (-3075 2450);
PAINT AQUA (-3075 2450);
DISPLAY INVISIBLE (-3075 2450);
FORCEPROP 2 LAST CDS_LIB mstr_symbols
J 0
(-3150 2500);
PAINT ORANGE (-3150 2500);
DISPLAY INVISIBLE (-3150 2500);
FORCEPROP 1 LAST VOLTAGE 0.0V
J 0
(-3195 2457);
DISPLAY 0.340426 (-3195 2457);
PAINT SKYBLUE (-3195 2457);
DISPLAY INVISIBLE (-3195 2457);
FORCEPROP 1 LAST BODY_TYPE PLUMBING
J 0
(-3195 2457);
DISPLAY 0.340426 (-3195 2457);
PAINT GREEN (-3195 2457);
DISPLAY INVISIBLE (-3195 2457);
FORCEPROP 1 LAST HDL_POWER GND
J 0
(-3150 2650);
DISPLAY 0.872340 (-3150 2650);
PAINT GREEN (-3150 2650);
DISPLAY INVISIBLE (-3150 2650);
FORCEADD OFFPAGE..2
(3700 2650);
FORCEPROP 2 LAST $XR0 187 
J 0
(3889 2650);
DISPLAY 0.638298 (3889 2650);
PAINT MONO (3889 2650);
FORCEPROP 2 LAST PATH I166
J 0
(3900 2700);
DISPLAY 1.021277 (3900 2700);
PAINT ORANGE (3900 2700);
DISPLAY INVISIBLE (3900 2700);
FORCEPROP 2 LAST CDS_LIB mstr_standard
J 0
(3700 2650);
PAINT ORANGE (3700 2650);
DISPLAY INVISIBLE (3700 2650);
FORCEPROP 1 LAST OFFPAGE TRUE
J 0
(4025 2525);
DISPLAY 0.872340 (4025 2525);
PAINT GREEN (4025 2525);
DISPLAY INVISIBLE (4025 2525);
FORCEPROP 1 LAST COMMENT_BODY TRUE
J 0
(3655 2555);
DISPLAY 0.872340 (3655 2555);
PAINT PEACH (3655 2555);
DISPLAY INVISIBLE (3655 2555);
FORCEADD OFFPAGE..2
(3700 2600);
FORCEPROP 2 LAST $XR0 187 
J 0
(3889 2600);
DISPLAY 0.638298 (3889 2600);
PAINT MONO (3889 2600);
FORCEPROP 2 LAST PATH I167
J 0
(3900 2650);
DISPLAY 1.021277 (3900 2650);
PAINT ORANGE (3900 2650);
DISPLAY INVISIBLE (3900 2650);
FORCEPROP 2 LAST CDS_LIB mstr_standard
J 0
(3700 2600);
PAINT ORANGE (3700 2600);
DISPLAY INVISIBLE (3700 2600);
FORCEPROP 1 LAST OFFPAGE TRUE
J 0
(4025 2475);
DISPLAY 0.872340 (4025 2475);
PAINT GREEN (4025 2475);
DISPLAY INVISIBLE (4025 2475);
FORCEPROP 1 LAST COMMENT_BODY TRUE
J 0
(3655 2505);
DISPLAY 0.872340 (3655 2505);
PAINT PEACH (3655 2505);
DISPLAY INVISIBLE (3655 2505);
FORCEADD OFFPAGE..2
(3700 2500);
FORCEPROP 2 LAST $XR0 187 
J 0
(3889 2500);
DISPLAY 0.638298 (3889 2500);
PAINT MONO (3889 2500);
FORCEPROP 2 LAST PATH I168
J 0
(3900 2550);
DISPLAY 1.021277 (3900 2550);
PAINT ORANGE (3900 2550);
DISPLAY INVISIBLE (3900 2550);
FORCEPROP 2 LAST CDS_LIB mstr_standard
J 0
(3700 2500);
PAINT ORANGE (3700 2500);
DISPLAY INVISIBLE (3700 2500);
FORCEPROP 1 LAST OFFPAGE TRUE
J 0
(4025 2375);
DISPLAY 0.872340 (4025 2375);
PAINT GREEN (4025 2375);
DISPLAY INVISIBLE (4025 2375);
FORCEPROP 1 LAST COMMENT_BODY TRUE
J 0
(3655 2405);
DISPLAY 0.872340 (3655 2405);
PAINT PEACH (3655 2405);
DISPLAY INVISIBLE (3655 2405);
FORCEADD OFFPAGE..2
(3700 2550);
FORCEPROP 2 LAST $XR0 187 
J 0
(3889 2550);
DISPLAY 0.638298 (3889 2550);
PAINT MONO (3889 2550);
FORCEPROP 2 LAST PATH I169
J 0
(3900 2600);
DISPLAY 1.021277 (3900 2600);
PAINT ORANGE (3900 2600);
DISPLAY INVISIBLE (3900 2600);
FORCEPROP 2 LAST CDS_LIB mstr_standard
J 0
(3700 2550);
PAINT ORANGE (3700 2550);
DISPLAY INVISIBLE (3700 2550);
FORCEPROP 1 LAST OFFPAGE TRUE
J 0
(4025 2425);
DISPLAY 0.872340 (4025 2425);
PAINT GREEN (4025 2425);
DISPLAY INVISIBLE (4025 2425);
FORCEPROP 1 LAST COMMENT_BODY TRUE
J 0
(3655 2455);
DISPLAY 0.872340 (3655 2455);
PAINT PEACH (3655 2455);
DISPLAY INVISIBLE (3655 2455);
FORCEADD OFFPAGE..2
(3700 2400);
FORCEPROP 2 LAST $XR0 186 
J 0
(3889 2400);
DISPLAY 0.638298 (3889 2400);
PAINT MONO (3889 2400);
FORCEPROP 2 LAST PATH I170
J 0
(3900 2450);
DISPLAY 1.021277 (3900 2450);
PAINT ORANGE (3900 2450);
DISPLAY INVISIBLE (3900 2450);
FORCEPROP 2 LAST CDS_LIB mstr_standard
J 0
(3700 2400);
PAINT ORANGE (3700 2400);
DISPLAY INVISIBLE (3700 2400);
FORCEPROP 1 LAST OFFPAGE TRUE
J 0
(4025 2275);
DISPLAY 0.872340 (4025 2275);
PAINT GREEN (4025 2275);
DISPLAY INVISIBLE (4025 2275);
FORCEPROP 1 LAST COMMENT_BODY TRUE
J 0
(3655 2305);
DISPLAY 0.872340 (3655 2305);
PAINT PEACH (3655 2305);
DISPLAY INVISIBLE (3655 2305);
FORCEADD OFFPAGE..2
(3700 2450);
FORCEPROP 2 LAST $XR0 186 
J 0
(3889 2450);
DISPLAY 0.638298 (3889 2450);
PAINT MONO (3889 2450);
FORCEPROP 2 LAST PATH I171
J 0
(3900 2500);
DISPLAY 1.021277 (3900 2500);
PAINT ORANGE (3900 2500);
DISPLAY INVISIBLE (3900 2500);
FORCEPROP 2 LAST CDS_LIB mstr_standard
J 0
(3700 2450);
PAINT ORANGE (3700 2450);
DISPLAY INVISIBLE (3700 2450);
FORCEPROP 1 LAST OFFPAGE TRUE
J 0
(4025 2325);
DISPLAY 0.872340 (4025 2325);
PAINT GREEN (4025 2325);
DISPLAY INVISIBLE (4025 2325);
FORCEPROP 1 LAST COMMENT_BODY TRUE
J 0
(3655 2355);
DISPLAY 0.872340 (3655 2355);
PAINT PEACH (3655 2355);
DISPLAY INVISIBLE (3655 2355);
FORCEADD OFFPAGE..2
(3700 2350);
FORCEPROP 2 LAST $XR0 186 
J 0
(3889 2350);
DISPLAY 0.638298 (3889 2350);
PAINT MONO (3889 2350);
FORCEPROP 2 LAST PATH I172
J 0
(3900 2400);
DISPLAY 1.021277 (3900 2400);
PAINT ORANGE (3900 2400);
DISPLAY INVISIBLE (3900 2400);
FORCEPROP 2 LAST CDS_LIB mstr_standard
J 0
(3700 2350);
PAINT ORANGE (3700 2350);
DISPLAY INVISIBLE (3700 2350);
FORCEPROP 1 LAST OFFPAGE TRUE
J 0
(4025 2225);
DISPLAY 0.872340 (4025 2225);
PAINT GREEN (4025 2225);
DISPLAY INVISIBLE (4025 2225);
FORCEPROP 1 LAST COMMENT_BODY TRUE
J 0
(3655 2255);
DISPLAY 0.872340 (3655 2255);
PAINT PEACH (3655 2255);
DISPLAY INVISIBLE (3655 2255);
FORCEADD OFFPAGE..2
(3700 2300);
FORCEPROP 2 LAST $XR0 186 
J 0
(3889 2300);
DISPLAY 0.638298 (3889 2300);
PAINT MONO (3889 2300);
FORCEPROP 2 LAST PATH I173
J 0
(3900 2350);
DISPLAY 1.021277 (3900 2350);
PAINT ORANGE (3900 2350);
DISPLAY INVISIBLE (3900 2350);
FORCEPROP 2 LAST CDS_LIB mstr_standard
J 0
(3700 2300);
PAINT ORANGE (3700 2300);
DISPLAY INVISIBLE (3700 2300);
FORCEPROP 1 LAST OFFPAGE TRUE
J 0
(4025 2175);
DISPLAY 0.872340 (4025 2175);
PAINT GREEN (4025 2175);
DISPLAY INVISIBLE (4025 2175);
FORCEPROP 1 LAST COMMENT_BODY TRUE
J 0
(3655 2205);
DISPLAY 0.872340 (3655 2205);
PAINT PEACH (3655 2205);
DISPLAY INVISIBLE (3655 2205);
FORCEADD OFFPAGE..5
R 2
(3700 3050);
FORCEPROP 2 LAST $XR0 185 
J 0
(3889 3050);
DISPLAY 0.638298 (3889 3050);
PAINT MONO (3889 3050);
FORCEPROP 2 LAST PATH I174
J 0
(3450 3100);
DISPLAY 1.021277 (3450 3100);
PAINT ORANGE (3450 3100);
DISPLAY INVISIBLE (3450 3100);
FORCEPROP 2 LAST CDS_LIB mstr_standard
J 0
(3700 3050);
PAINT ORANGE (3700 3050);
DISPLAY INVISIBLE (3700 3050);
FORCEPROP 1 LAST OFFPAGE TRUE
J 2
(3375 2925);
DISPLAY 0.872340 (3375 2925);
PAINT GREEN (3375 2925);
DISPLAY INVISIBLE (3375 2925);
FORCEPROP 1 LAST COMMENT_BODY TRUE
J 2
(3600 2975);
DISPLAY 0.872340 (3600 2975);
PAINT GREEN (3600 2975);
DISPLAY INVISIBLE (3600 2975);
FORCEADD OFFPAGE..5
R 2
(3700 3000);
FORCEPROP 2 LAST $XR0 185 
J 0
(3889 3000);
DISPLAY 0.638298 (3889 3000);
PAINT MONO (3889 3000);
FORCEPROP 2 LAST PATH I175
J 0
(3450 3050);
DISPLAY 1.021277 (3450 3050);
PAINT ORANGE (3450 3050);
DISPLAY INVISIBLE (3450 3050);
FORCEPROP 2 LAST CDS_LIB mstr_standard
J 0
(3700 3000);
PAINT ORANGE (3700 3000);
DISPLAY INVISIBLE (3700 3000);
FORCEPROP 1 LAST OFFPAGE TRUE
J 2
(3375 2875);
DISPLAY 0.872340 (3375 2875);
PAINT GREEN (3375 2875);
DISPLAY INVISIBLE (3375 2875);
FORCEPROP 1 LAST COMMENT_BODY TRUE
J 2
(3600 2925);
DISPLAY 0.872340 (3600 2925);
PAINT GREEN (3600 2925);
DISPLAY INVISIBLE (3600 2925);
FORCEADD OFFPAGE..5
(-2350 2800);
FORCEPROP 2 LAST $XR0 145 
J 0
(-2605 2800);
DISPLAY 0.638298 (-2605 2800);
PAINT MONO (-2605 2800);
FORCEPROP 2 LAST CDS_LIB mstr_standard
J 0
(-2350 2800);
PAINT ORANGE (-2350 2800);
DISPLAY INVISIBLE (-2350 2800);
FORCEPROP 2 LAST PATH I180
J 0
(-2600 2850);
DISPLAY 1.021277 (-2600 2850);
PAINT ORANGE (-2600 2850);
DISPLAY INVISIBLE (-2600 2850);
FORCEPROP 1 LAST OFFPAGE TRUE
J 0
(-2025 2675);
DISPLAY 0.872340 (-2025 2675);
PAINT GREEN (-2025 2675);
DISPLAY INVISIBLE (-2025 2675);
FORCEPROP 1 LAST COMMENT_BODY TRUE
J 0
(-2250 2725);
DISPLAY 0.872340 (-2250 2725);
PAINT GREEN (-2250 2725);
DISPLAY INVISIBLE (-2250 2725);
FORCEADD OFFPAGE..2
(3700 2900);
FORCEPROP 2 LAST $XR0 139 
J 0
(3889 2900);
DISPLAY 0.638298 (3889 2900);
PAINT MONO (3889 2900);
FORCEPROP 2 LAST CDS_LIB mstr_standard
J 0
(3700 2900);
PAINT ORANGE (3700 2900);
DISPLAY INVISIBLE (3700 2900);
FORCEPROP 2 LAST PATH I181
J 0
(3450 2950);
DISPLAY 1.021277 (3450 2950);
PAINT ORANGE (3450 2950);
DISPLAY INVISIBLE (3450 2950);
FORCEPROP 1 LAST OFFPAGE TRUE
J 0
(4025 2775);
DISPLAY 0.872340 (4025 2775);
PAINT GREEN (4025 2775);
DISPLAY INVISIBLE (4025 2775);
FORCEPROP 1 LAST COMMENT_BODY TRUE
J 0
(3655 2805);
DISPLAY 0.872340 (3655 2805);
PAINT GREEN (3655 2805);
DISPLAY INVISIBLE (3655 2805);
FORCEADD OFFPAGE..2
(3700 2950);
FORCEPROP 2 LAST $XR0 139 
J 0
(3889 2950);
DISPLAY 0.638298 (3889 2950);
PAINT MONO (3889 2950);
FORCEPROP 2 LAST CDS_LIB mstr_standard
J 0
(3700 2950);
PAINT ORANGE (3700 2950);
DISPLAY INVISIBLE (3700 2950);
FORCEPROP 2 LAST PATH I182
J 0
(3450 3000);
DISPLAY 1.021277 (3450 3000);
PAINT ORANGE (3450 3000);
DISPLAY INVISIBLE (3450 3000);
FORCEPROP 1 LAST OFFPAGE TRUE
J 0
(4025 2825);
DISPLAY 0.872340 (4025 2825);
PAINT GREEN (4025 2825);
DISPLAY INVISIBLE (4025 2825);
FORCEPROP 1 LAST COMMENT_BODY TRUE
J 0
(3655 2855);
DISPLAY 0.872340 (3655 2855);
PAINT GREEN (3655 2855);
DISPLAY INVISIBLE (3655 2855);
FORCEADD OFFPAGE..2
(3700 1550);
FORCEPROP 2 LAST $XR0 181 
J 0
(3889 1550);
DISPLAY 0.638298 (3889 1550);
PAINT MONO (3889 1550);
FORCEPROP 2 LAST PATH I183
J 0
(3900 1600);
DISPLAY 1.021277 (3900 1600);
PAINT ORANGE (3900 1600);
DISPLAY INVISIBLE (3900 1600);
FORCEPROP 2 LAST CDS_LIB mstr_standard
J 0
(3700 1550);
PAINT ORANGE (3700 1550);
DISPLAY INVISIBLE (3700 1550);
FORCEPROP 1 LAST OFFPAGE TRUE
J 0
(4025 1425);
DISPLAY 0.872340 (4025 1425);
PAINT GREEN (4025 1425);
DISPLAY INVISIBLE (4025 1425);
FORCEPROP 1 LAST COMMENT_BODY TRUE
J 0
(3655 1455);
DISPLAY 0.872340 (3655 1455);
PAINT PEACH (3655 1455);
DISPLAY INVISIBLE (3655 1455);
FORCEADD OFFPAGE..2
(3700 1500);
FORCEPROP 2 LAST $XR0 181 
J 0
(3889 1500);
DISPLAY 0.638298 (3889 1500);
PAINT MONO (3889 1500);
FORCEPROP 2 LAST PATH I184
J 0
(3900 1550);
DISPLAY 1.021277 (3900 1550);
PAINT ORANGE (3900 1550);
DISPLAY INVISIBLE (3900 1550);
FORCEPROP 2 LAST CDS_LIB mstr_standard
J 0
(3700 1500);
PAINT ORANGE (3700 1500);
DISPLAY INVISIBLE (3700 1500);
FORCEPROP 1 LAST OFFPAGE TRUE
J 0
(4025 1375);
DISPLAY 0.872340 (4025 1375);
PAINT GREEN (4025 1375);
DISPLAY INVISIBLE (4025 1375);
FORCEPROP 1 LAST COMMENT_BODY TRUE
J 0
(3655 1405);
DISPLAY 0.872340 (3655 1405);
PAINT PEACH (3655 1405);
DISPLAY INVISIBLE (3655 1405);
FORCEADD OFFPAGE..2
(3700 1650);
FORCEPROP 2 LAST $XR0 102 
J 0
(3889 1650);
DISPLAY 0.638298 (3889 1650);
PAINT MONO (3889 1650);
FORCEPROP 2 LAST PATH I185
J 0
(3900 1700);
DISPLAY 1.021277 (3900 1700);
PAINT ORANGE (3900 1700);
DISPLAY INVISIBLE (3900 1700);
FORCEPROP 2 LAST CDS_LIB mstr_standard
J 0
(3700 1650);
PAINT ORANGE (3700 1650);
DISPLAY INVISIBLE (3700 1650);
FORCEPROP 1 LAST OFFPAGE TRUE
J 0
(4025 1525);
DISPLAY 0.872340 (4025 1525);
PAINT GREEN (4025 1525);
DISPLAY INVISIBLE (4025 1525);
FORCEPROP 1 LAST COMMENT_BODY TRUE
J 0
(3655 1555);
DISPLAY 0.872340 (3655 1555);
PAINT PEACH (3655 1555);
DISPLAY INVISIBLE (3655 1555);
FORCEADD OFFPAGE..2
(3700 1600);
FORCEPROP 2 LAST $XR0 102 
J 0
(3889 1600);
DISPLAY 0.638298 (3889 1600);
PAINT MONO (3889 1600);
FORCEPROP 2 LAST PATH I186
J 0
(3900 1650);
DISPLAY 1.021277 (3900 1650);
PAINT ORANGE (3900 1650);
DISPLAY INVISIBLE (3900 1650);
FORCEPROP 2 LAST CDS_LIB mstr_standard
J 0
(3700 1600);
PAINT ORANGE (3700 1600);
DISPLAY INVISIBLE (3700 1600);
FORCEPROP 1 LAST OFFPAGE TRUE
J 0
(4025 1475);
DISPLAY 0.872340 (4025 1475);
PAINT GREEN (4025 1475);
DISPLAY INVISIBLE (4025 1475);
FORCEPROP 1 LAST COMMENT_BODY TRUE
J 0
(3655 1505);
DISPLAY 0.872340 (3655 1505);
PAINT PEACH (3655 1505);
DISPLAY INVISIBLE (3655 1505);
FORCEADD RES..1
(-1625 2850);
FORCEPROP 0 LAST GROUP AST2500
J 0
(-1725 2800);
DISPLAY 0.638298 (-1725 2800);
PAINT BROWN (-1725 2800);
DISPLAY BOTH (-1725 2800);
FORCEPROP 1 LAST PART_NUMBER G21497-005
J 0
(-1700 2950);
DISPLAY 0.617021 (-1700 2950);
PAINT BLUE (-1700 2950);
FORCEPROP 1 LAST TOLERANCE 5%
J 0
(-1700 2900);
DISPLAY 0.617021 (-1700 2900);
PAINT SKYBLUE (-1700 2900);
FORCEPROP 1 LAST VALUE 0.0
J 2
(-1725 2900);
DISPLAY 0.617021 (-1725 2900);
PAINT SKYBLUE (-1725 2900);
FORCEPROP 1 LASTPIN (-1725 2850) $PN 1
J 0
(-1713 2862);
DISPLAY 0.617021 (-1713 2862);
PAINT WHITE (-1713 2862);
FORCEPROP 1 LAST PACK_TYPE 0402
J 0
(-1600 2900);
DISPLAY 0.617021 (-1600 2900);
PAINT SKYBLUE (-1600 2900);
FORCEPROP 1 LASTPIN (-1525 2850) $PN 2
J 0
(-1563 2862);
DISPLAY 0.617021 (-1563 2862);
PAINT WHITE (-1563 2862);
FORCEPROP 1 LAST WATTAGE 1/16W
J 2
(-1375 2950);
DISPLAY 0.510638 (-1375 2950);
PAINT SKYBLUE (-1375 2950);
FORCEPROP 1 LAST LOCATION R7C4
J 0
(-1925 2950);
DISPLAY 0.617021 (-1925 2950);
PAINT AQUA (-1925 2950);
FORCEPROP 2 LAST CDS_LOCATION R7C4
J 0
(-2100 2850);
DISPLAY 0.617021 (-2100 2850);
PAINT AQUA (-2100 2850);
DISPLAY INVISIBLE (-2100 2850);
FORCEPROP 1 LAST PATH I191
J 0
(-1675 3000);
DISPLAY 0.978723 (-1675 3000);
PAINT WHITE (-1675 3000);
DISPLAY INVISIBLE (-1675 3000);
FORCEPROP 2 LAST ROOM CPU0
J 0
(-1675 3000);
PAINT PEACH (-1675 3000);
DISPLAY INVISIBLE (-1675 3000);
FORCEPROP 2 LAST SEC 1
J 0
(-1675 3075);
DISPLAY 0.680851 (-1675 3075);
PAINT MONO (-1675 3075);
DISPLAY INVISIBLE (-1675 3075);
FORCEPROP 2 LAST SEC_TYPE 0402
J 0
(-1675 3075);
DISPLAY 1.021277 (-1675 3075);
PAINT ORANGE (-1675 3075);
DISPLAY INVISIBLE (-1675 3075);
FORCEPROP 2 LAST CDS_LIB mstr_discrete
J 0
(-1625 2850);
DISPLAY 1.340426 (-1625 2850);
PAINT ORANGE (-1625 2850);
DISPLAY INVISIBLE (-1625 2850);
FORCEPROP 2 LAST BOM_COST PROC_SIDEBAND
J 0
(-1625 2850);
PAINT MONO (-1625 2850);
DISPLAY INVISIBLE (-1625 2850);
FORCEPROP 1 LAST MATERIAL CHIP
J 0
(-1475 2750);
DISPLAY 0.510638 (-1475 2750);
PAINT SKYBLUE (-1475 2750);
DISPLAY INVISIBLE (-1475 2750);
FORCEADD RES..1
(-1275 2800);
FORCEPROP 1 LAST VALUE 0.0
J 2
(-1375 2850);
DISPLAY 0.617021 (-1375 2850);
PAINT SKYBLUE (-1375 2850);
FORCEPROP 0 LAST GROUP AST2500
J 0
(-1375 2750);
DISPLAY 0.638298 (-1375 2750);
PAINT BROWN (-1375 2750);
DISPLAY BOTH (-1375 2750);
FORCEPROP 1 LASTPIN (-1175 2800) $PN 2
J 0
(-1213 2812);
DISPLAY 0.617021 (-1213 2812);
PAINT WHITE (-1213 2812);
FORCEPROP 1 LASTPIN (-1375 2800) $PN 1
J 0
(-1363 2812);
DISPLAY 0.617021 (-1363 2812);
PAINT WHITE (-1363 2812);
FORCEPROP 1 LAST TOLERANCE 5%
J 0
(-1350 2850);
DISPLAY 0.617021 (-1350 2850);
PAINT SKYBLUE (-1350 2850);
FORCEPROP 1 LAST PACK_TYPE 0402
J 0
(-1250 2850);
DISPLAY 0.617021 (-1250 2850);
PAINT SKYBLUE (-1250 2850);
FORCEPROP 1 LAST LOCATION R7C2
J 0
(-1475 2900);
DISPLAY 0.617021 (-1475 2900);
PAINT AQUA (-1475 2900);
FORCEPROP 1 LAST WATTAGE 1/16W
J 2
(-975 2900);
DISPLAY 0.510638 (-975 2900);
PAINT SKYBLUE (-975 2900);
FORCEPROP 1 LAST PART_NUMBER G21497-005
J 0
(-1350 2900);
DISPLAY 0.617021 (-1350 2900);
PAINT BLUE (-1350 2900);
FORCEPROP 2 LAST CDS_LOCATION R7C2
J 0
(-1750 2800);
DISPLAY 0.617021 (-1750 2800);
PAINT AQUA (-1750 2800);
DISPLAY INVISIBLE (-1750 2800);
FORCEPROP 2 LAST ROOM CPU0
J 0
(-1325 2950);
PAINT PEACH (-1325 2950);
DISPLAY INVISIBLE (-1325 2950);
FORCEPROP 2 LAST SEC 1
J 0
(-1325 3025);
DISPLAY 0.680851 (-1325 3025);
PAINT MONO (-1325 3025);
DISPLAY INVISIBLE (-1325 3025);
FORCEPROP 2 LAST SEC_TYPE 0402
J 0
(-1325 3025);
DISPLAY 1.021277 (-1325 3025);
PAINT ORANGE (-1325 3025);
DISPLAY INVISIBLE (-1325 3025);
FORCEPROP 2 LAST CDS_LIB mstr_discrete
J 0
(-1275 2800);
DISPLAY 1.340426 (-1275 2800);
PAINT ORANGE (-1275 2800);
DISPLAY INVISIBLE (-1275 2800);
FORCEPROP 2 LAST BOM_COST PROC_SIDEBAND
J 0
(-1275 2800);
PAINT MONO (-1275 2800);
DISPLAY INVISIBLE (-1275 2800);
FORCEPROP 1 LAST MATERIAL CHIP
J 0
(-1125 2700);
DISPLAY 0.510638 (-1125 2700);
PAINT SKYBLUE (-1125 2700);
DISPLAY INVISIBLE (-1125 2700);
FORCEPROP 1 LAST PATH I192
J 0
(-1325 2950);
DISPLAY 0.978723 (-1325 2950);
PAINT WHITE (-1325 2950);
DISPLAY INVISIBLE (-1325 2950);
FORCEADD CAP..1
(-2850 2750);
FORCEPROP 1 LAST LOCATION C3W1
J 0
(-2800 2850);
DISPLAY 0.638298 (-2800 2850);
PAINT SKYBLUE (-2800 2850);
FORCEPROP 1 LASTPIN (-2850 2850) $PN 1
J 0
(-2840 2830);
DISPLAY 0.787234 (-2840 2830);
PAINT ORANGE (-2840 2830);
FORCEPROP 1 LASTPIN (-2850 2650) $PN 2
J 0
(-2840 2630);
DISPLAY 0.787234 (-2840 2630);
PAINT ORANGE (-2840 2630);
FORCEPROP 1 LAST PACK_TYPE 0402
J 0
(-2800 2550);
DISPLAY 0.638298 (-2800 2550);
PAINT SKYBLUE (-2800 2550);
FORCEPROP 1 LAST TOLERANCE 10%
J 0
(-2800 2700);
DISPLAY 0.638298 (-2800 2700);
PAINT SKYBLUE (-2800 2700);
FORCEPROP 1 LAST VOLTAGE 6.3V
J 0
(-2800 2750);
DISPLAY 0.638298 (-2800 2750);
PAINT SKYBLUE (-2800 2750);
FORCEPROP 1 LAST VALUE 1.0UF
J 0
(-2800 2800);
DISPLAY 0.638298 (-2800 2800);
PAINT SKYBLUE (-2800 2800);
FORCEPROP 1 LAST MATERIAL EMPTY
J 0
(-2800 2650);
DISPLAY 0.638298 (-2800 2650);
PAINT RED (-2800 2650);
FORCEPROP 1 LAST PART_NUMBER D97712-004
J 0
(-2800 2600);
DISPLAY 0.638298 (-2800 2600);
PAINT BLUE (-2800 2600);
FORCEPROP 2 LAST CDS_LIB mstr_discrete
J 0
(-2850 2750);
PAINT MONO (-2850 2750);
DISPLAY INVISIBLE (-2850 2750);
FORCEPROP 2 LAST SEC_TYPE 0402
J 0
(-2800 2950);
DISPLAY 1.021277 (-2800 2950);
PAINT ORANGE (-2800 2950);
DISPLAY INVISIBLE (-2800 2950);
FORCEPROP 2 LAST SEC 1
J 0
(-2800 2950);
DISPLAY 0.680851 (-2800 2950);
PAINT MONO (-2800 2950);
DISPLAY INVISIBLE (-2800 2950);
FORCEPROP 1 LAST PATH I193
J 0
(-2800 2900);
DISPLAY 0.978723 (-2800 2900);
PAINT WHITE (-2800 2900);
DISPLAY INVISIBLE (-2800 2900);
FORCEADD GND..1
(-2850 2500);
FORCEPROP 3 LASTPIN (-2850 2550) SIG_NAME GND\g
J 0
(-2840 2560);
DISPLAY 0.659574 (-2840 2560);
PAINT MONO (-2840 2560);
DISPLAY INVISIBLE (-2840 2560);
FORCEPROP 1 LAST VOLTAGE 0.0V
J 0
(-2895 2457);
DISPLAY 0.340426 (-2895 2457);
PAINT SKYBLUE (-2895 2457);
DISPLAY INVISIBLE (-2895 2457);
FORCEPROP 2 LAST CDS_LIB mstr_symbols
J 0
(-2850 2500);
PAINT ORANGE (-2850 2500);
DISPLAY INVISIBLE (-2850 2500);
FORCEPROP 1 LAST SIZE 1B
J 0
(-2775 2450);
DISPLAY 0.872340 (-2775 2450);
PAINT AQUA (-2775 2450);
DISPLAY INVISIBLE (-2775 2450);
FORCEPROP 1 LAST PATH I194
J 0
(-2775 2500);
DISPLAY 0.872340 (-2775 2500);
PAINT AQUA (-2775 2500);
DISPLAY INVISIBLE (-2775 2500);
FORCEPROP 1 LAST BODY_TYPE PLUMBING
J 0
(-2895 2457);
DISPLAY 0.340426 (-2895 2457);
PAINT GREEN (-2895 2457);
DISPLAY INVISIBLE (-2895 2457);
FORCEPROP 1 LAST HDL_POWER GND
J 0
(-2850 2650);
DISPLAY 0.872340 (-2850 2650);
PAINT GREEN (-2850 2650);
DISPLAY INVISIBLE (-2850 2650);
FORCEADD CAP..1
(-275 -225);
FORCEPROP 1 LAST VALUE 15.0PF
J 0
(-225 -175);
DISPLAY 0.617021 (-225 -175);
PAINT SKYBLUE (-225 -175);
FORCEPROP 1 LAST VOLTAGE 50V
J 0
(-225 -225);
DISPLAY 0.617021 (-225 -225);
PAINT SKYBLUE (-225 -225);
FORCEPROP 1 LAST LOCATION C7C13
J 0
(-225 -125);
DISPLAY 0.617021 (-225 -125);
PAINT AQUA (-225 -125);
FORCEPROP 1 LAST PART_NUMBER A36095-047
J 0
(-225 -375);
DISPLAY 0.617021 (-225 -375);
PAINT BLUE (-225 -375);
FORCEPROP 1 LASTPIN (-275 -325) $PN 2
J 0
(-265 -345);
DISPLAY 0.617021 (-265 -345);
PAINT ORANGE (-265 -345);
FORCEPROP 1 LAST TOLERANCE 5%
J 0
(-225 -275);
DISPLAY 0.617021 (-225 -275);
PAINT SKYBLUE (-225 -275);
FORCEPROP 1 LAST MATERIAL COG
J 0
(-225 -325);
DISPLAY 0.617021 (-225 -325);
PAINT SKYBLUE (-225 -325);
FORCEPROP 1 LAST PACK_TYPE 0402LF
J 0
(-225 -425);
DISPLAY 0.617021 (-225 -425);
PAINT SKYBLUE (-225 -425);
FORCEPROP 1 LASTPIN (-275 -125) $PN 1
J 0
(-265 -145);
DISPLAY 0.617021 (-265 -145);
PAINT ORANGE (-265 -145);
FORCEPROP 1 LAST PATH I195
J 0
(-225 -75);
DISPLAY 0.978723 (-225 -75);
PAINT WHITE (-225 -75);
DISPLAY INVISIBLE (-225 -75);
FORCEPROP 2 LAST SEC_TYPE 0402LF
J 0
(-225 -25);
DISPLAY 1.021277 (-225 -25);
PAINT ORANGE (-225 -25);
DISPLAY INVISIBLE (-225 -25);
FORCEPROP 2 LAST SEC 1
J 0
(-225 -25);
DISPLAY 0.680851 (-225 -25);
PAINT MONO (-225 -25);
DISPLAY INVISIBLE (-225 -25);
FORCEPROP 2 LAST CDS_LIB mstr_discrete
J 0
(-275 -225);
PAINT ORANGE (-275 -225);
DISPLAY INVISIBLE (-275 -225);
FORCEPROP 2 LAST ROOM SB
J 0
(-275 -225);
PAINT MONO (-275 -225);
DISPLAY INVISIBLE (-275 -225);
FORCEPROP 2 LAST BOM_COST SYS_CLOCK
J 0
(-135 -415);
PAINT MONO (-135 -415);
DISPLAY INVISIBLE (-135 -415);
FORCEPROP 2 LAST CDS_LOCATION C7C13
J 0
(-225 -125);
DISPLAY 0.617021 (-225 -125);
PAINT AQUA (-225 -125);
DISPLAY INVISIBLE (-225 -125);
FORCEADD CAP..1
(225 -225);
FORCEPROP 1 LAST LOCATION C7C15
J 0
(275 -125);
DISPLAY 0.617021 (275 -125);
PAINT AQUA (275 -125);
FORCEPROP 1 LASTPIN (225 -125) $PN 1
J 0
(235 -145);
DISPLAY 0.617021 (235 -145);
PAINT ORANGE (235 -145);
FORCEPROP 1 LAST VALUE 15.0PF
J 0
(275 -175);
DISPLAY 0.617021 (275 -175);
PAINT SKYBLUE (275 -175);
FORCEPROP 1 LAST VOLTAGE 50V
J 0
(275 -225);
DISPLAY 0.617021 (275 -225);
PAINT SKYBLUE (275 -225);
FORCEPROP 1 LAST MATERIAL COG
J 0
(275 -325);
DISPLAY 0.617021 (275 -325);
PAINT SKYBLUE (275 -325);
FORCEPROP 1 LASTPIN (225 -325) $PN 2
J 0
(235 -345);
DISPLAY 0.617021 (235 -345);
PAINT ORANGE (235 -345);
FORCEPROP 1 LAST TOLERANCE 5%
J 0
(275 -275);
DISPLAY 0.617021 (275 -275);
PAINT SKYBLUE (275 -275);
FORCEPROP 1 LAST PART_NUMBER A36095-047
J 0
(275 -375);
DISPLAY 0.617021 (275 -375);
PAINT BLUE (275 -375);
FORCEPROP 1 LAST PACK_TYPE 0402LF
J 0
(275 -425);
DISPLAY 0.617021 (275 -425);
PAINT SKYBLUE (275 -425);
FORCEPROP 1 LAST PATH I196
J 0
(275 -75);
DISPLAY 0.978723 (275 -75);
PAINT WHITE (275 -75);
DISPLAY INVISIBLE (275 -75);
FORCEPROP 2 LAST SEC_TYPE 0402LF
J 0
(275 -25);
DISPLAY 1.021277 (275 -25);
PAINT ORANGE (275 -25);
DISPLAY INVISIBLE (275 -25);
FORCEPROP 2 LAST SEC 1
J 0
(275 -25);
DISPLAY 0.680851 (275 -25);
PAINT MONO (275 -25);
DISPLAY INVISIBLE (275 -25);
FORCEPROP 2 LAST CDS_LIB mstr_discrete
J 0
(225 -225);
PAINT ORANGE (225 -225);
DISPLAY INVISIBLE (225 -225);
FORCEPROP 2 LAST ROOM SB
J 0
(225 -225);
PAINT MONO (225 -225);
DISPLAY INVISIBLE (225 -225);
FORCEPROP 2 LAST BOM_COST SYS_CLOCK
J 0
(365 -415);
PAINT MONO (365 -415);
DISPLAY INVISIBLE (365 -415);
FORCEPROP 2 LAST CDS_LOCATION C7C15
J 0
(275 -125);
DISPLAY 0.617021 (275 -125);
PAINT AQUA (275 -125);
DISPLAY INVISIBLE (275 -125);
FORCEADD OFFPAGE..2
(3700 1700);
FORCEPROP 2 LAST $XR0 108 
J 0
(3889 1700);
DISPLAY 0.638298 (3889 1700);
PAINT MONO (3889 1700);
FORCEPROP 2 LAST PATH I35
J 0
(3875 1775);
DISPLAY 1.021277 (3875 1775);
PAINT ORANGE (3875 1775);
DISPLAY INVISIBLE (3875 1775);
FORCEPROP 2 LAST CDS_LIB mstr_standard
J 0
(3700 1700);
PAINT ORANGE (3700 1700);
DISPLAY INVISIBLE (3700 1700);
FORCEPROP 1 LAST OFFPAGE TRUE
J 0
(4025 1575);
DISPLAY 0.872340 (4025 1575);
PAINT GREEN (4025 1575);
DISPLAY INVISIBLE (4025 1575);
FORCEPROP 1 LAST COMMENT_BODY TRUE
J 0
(3655 1605);
DISPLAY 0.872340 (3655 1605);
PAINT PEACH (3655 1605);
DISPLAY INVISIBLE (3655 1605);
FORCEADD OFFPAGE..2
(3700 1750);
FORCEPROP 2 LAST $XR0 108 
J 0
(3889 1750);
DISPLAY 0.638298 (3889 1750);
PAINT MONO (3889 1750);
FORCEPROP 2 LAST PATH I36
J 0
(3875 1825);
DISPLAY 1.021277 (3875 1825);
PAINT ORANGE (3875 1825);
DISPLAY INVISIBLE (3875 1825);
FORCEPROP 2 LAST CDS_LIB mstr_standard
J 0
(3700 1750);
PAINT ORANGE (3700 1750);
DISPLAY INVISIBLE (3700 1750);
FORCEPROP 1 LAST OFFPAGE TRUE
J 0
(4025 1625);
DISPLAY 0.872340 (4025 1625);
PAINT GREEN (4025 1625);
DISPLAY INVISIBLE (4025 1625);
FORCEPROP 1 LAST COMMENT_BODY TRUE
J 0
(3655 1655);
DISPLAY 0.872340 (3655 1655);
PAINT PEACH (3655 1655);
DISPLAY INVISIBLE (3655 1655);
FORCEADD LBG_CORE_QAT_EXT_D..1
(525 2150);
FORCEPROP 2 LASTPIN (1525 2850) $PN A24
J 0
(1535 2860);
DISPLAY 0.617021 (1535 2860);
PAINT ORANGE (1535 2860);
FORCEPROP 2 LASTPIN (1525 2600) $PN B21
J 0
(1535 2610);
DISPLAY 0.617021 (1535 2610);
PAINT ORANGE (1535 2610);
FORCEPROP 2 LASTPIN (1525 2500) $PN B23
J 0
(1535 2510);
DISPLAY 0.617021 (1535 2510);
PAINT ORANGE (1535 2510);
FORCEPROP 2 LASTPIN (1525 2950) $PN A20
J 0
(1535 2960);
DISPLAY 0.617021 (1535 2960);
PAINT ORANGE (1535 2960);
FORCEPROP 2 LASTPIN (1525 2650) $PN D21
J 0
(1535 2660);
DISPLAY 0.617021 (1535 2660);
PAINT ORANGE (1535 2660);
FORCEPROP 2 LASTPIN (1525 2700) $PN K24
J 0
(1535 2710);
DISPLAY 0.617021 (1535 2710);
PAINT ORANGE (1535 2710);
FORCEPROP 2 LASTPIN (1525 2750) $PN H24
J 0
(1535 2760);
DISPLAY 0.617021 (1535 2760);
PAINT ORANGE (1535 2760);
FORCEPROP 2 LASTPIN (1525 2800) $PN C24
J 0
(1535 2810);
DISPLAY 0.617021 (1535 2810);
PAINT ORANGE (1535 2810);
FORCEPROP 2 LASTPIN (-475 2500) $PN B38
J 2
(-485 2510);
DISPLAY 0.617021 (-485 2510);
PAINT ORANGE (-485 2510);
FORCEPROP 2 LASTPIN (-475 2850) $PN D29
J 2
(-485 2860);
DISPLAY 0.617021 (-485 2860);
PAINT ORANGE (-485 2860);
FORCEPROP 2 LASTPIN (-475 2550) $PN D38
J 2
(-485 2560);
DISPLAY 0.617021 (-485 2560);
PAINT ORANGE (-485 2560);
FORCEPROP 2 LASTPIN (-475 2300) $PN K17
J 2
(-485 2310);
DISPLAY 0.617021 (-485 2310);
PAINT ORANGE (-485 2310);
FORCEPROP 1 LAST MATERIAL IC
J 0
(-425 3250);
DISPLAY 0.617021 (-425 3250);
PAINT SKYBLUE (-425 3250);
FORCEPROP 2 LASTPIN (1525 2050) $PN G40
J 0
(1535 2060);
DISPLAY 0.617021 (1535 2060);
PAINT ORANGE (1535 2060);
FORCEPROP 2 LASTPIN (1525 2900) $PN C20
J 0
(1535 2910);
DISPLAY 0.617021 (1535 2910);
PAINT ORANGE (1535 2910);
FORCEPROP 2 LASTPIN (1525 2400) $PN J26
J 0
(1535 2410);
DISPLAY 0.617021 (1535 2410);
PAINT ORANGE (1535 2410);
FORCEPROP 2 LASTPIN (1525 2300) $PN D31
J 0
(1535 2310);
DISPLAY 0.617021 (1535 2310);
PAINT ORANGE (1535 2310);
FORCEPROP 2 LASTPIN (1525 2200) $PN H31
J 0
(1535 2210);
DISPLAY 0.617021 (1535 2210);
PAINT ORANGE (1535 2210);
FORCEPROP 2 LASTPIN (1525 2100) $PN D33
J 0
(1535 2110);
DISPLAY 0.617021 (1535 2110);
PAINT ORANGE (1535 2110);
FORCEPROP 2 LASTPIN (1525 2550) $PN D23
J 0
(1535 2560);
DISPLAY 0.617021 (1535 2560);
PAINT ORANGE (1535 2560);
FORCEPROP 2 LASTPIN (1525 2350) $PN B31
J 0
(1535 2360);
DISPLAY 0.617021 (1535 2360);
PAINT ORANGE (1535 2360);
FORCEPROP 2 LASTPIN (1525 2250) $PN K31
J 0
(1535 2260);
DISPLAY 0.617021 (1535 2260);
PAINT ORANGE (1535 2260);
FORCEPROP 2 LASTPIN (1525 2150) $PN B33
J 0
(1535 2160);
DISPLAY 0.617021 (1535 2160);
PAINT ORANGE (1535 2160);
FORCEPROP 2 LASTPIN (1525 2000) $PN J40
J 0
(1535 2010);
DISPLAY 0.617021 (1535 2010);
PAINT ORANGE (1535 2010);
FORCEPROP 2 LASTPIN (1525 1900) $PN A28
J 0
(1535 1910);
DISPLAY 0.617021 (1535 1910);
PAINT ORANGE (1535 1910);
FORCEPROP 2 LASTPIN (1525 1800) $PN K42
J 0
(1535 1810);
DISPLAY 0.617021 (1535 1810);
PAINT ORANGE (1535 1810);
FORCEPROP 2 LASTPIN (1525 1700) $PN J33
J 0
(1535 1710);
DISPLAY 0.617021 (1535 1710);
PAINT ORANGE (1535 1710);
FORCEPROP 2 LASTPIN (1525 1600) $PN K35
J 0
(1535 1610);
DISPLAY 0.617021 (1535 1610);
PAINT ORANGE (1535 1610);
FORCEPROP 2 LASTPIN (1525 1500) $PN K38
J 0
(1535 1510);
DISPLAY 0.617021 (1535 1510);
PAINT ORANGE (1535 1510);
FORCEPROP 2 LASTPIN (1525 1950) $PN C28
J 0
(1535 1960);
DISPLAY 0.617021 (1535 1960);
PAINT ORANGE (1535 1960);
FORCEPROP 2 LASTPIN (1525 1850) $PN H42
J 0
(1535 1860);
DISPLAY 0.617021 (1535 1860);
PAINT ORANGE (1535 1860);
FORCEPROP 2 LASTPIN (1525 1750) $PN G33
J 0
(1535 1760);
DISPLAY 0.617021 (1535 1760);
PAINT ORANGE (1535 1760);
FORCEPROP 2 LASTPIN (1525 1650) $PN H35
J 0
(1535 1660);
DISPLAY 0.617021 (1535 1660);
PAINT ORANGE (1535 1660);
FORCEPROP 2 LASTPIN (1525 1550) $PN H38
J 0
(1535 1560);
DISPLAY 0.617021 (1535 1560);
PAINT ORANGE (1535 1560);
FORCEPROP 2 LASTPIN (1525 1300) $PN BW50
J 0
(1535 1310);
DISPLAY 0.617021 (1535 1310);
PAINT ORANGE (1535 1310);
FORCEPROP 2 LASTPIN (1525 1350) $PN BY51
J 0
(1535 1360);
DISPLAY 0.617021 (1535 1360);
PAINT ORANGE (1535 1360);
FORCEPROP 2 LASTPIN (-475 2450) $PN C39
J 2
(-485 2460);
DISPLAY 0.617021 (-485 2460);
PAINT ORANGE (-485 2460);
FORCEPROP 2 LASTPIN (-475 2700) $PN A32
J 2
(-485 2710);
DISPLAY 0.617021 (-485 2710);
PAINT ORANGE (-485 2710);
FORCEPROP 2 LASTPIN (-475 2750) $PN C32
J 2
(-485 2760);
DISPLAY 0.617021 (-485 2760);
PAINT ORANGE (-485 2760);
FORCEPROP 2 LASTPIN (-475 2800) $PN B29
J 2
(-485 2810);
DISPLAY 0.617021 (-485 2810);
PAINT ORANGE (-485 2810);
FORCEPROP 2 LASTPIN (-475 2650) $PN D40
J 2
(-485 2660);
DISPLAY 0.617021 (-485 2660);
PAINT ORANGE (-485 2660);
FORCEPROP 2 LASTPIN (-475 3000) $PN C26
J 2
(-485 3010);
DISPLAY 0.617021 (-485 3010);
PAINT ORANGE (-485 3010);
FORCEPROP 2 LASTPIN (-475 2950) $PN G44
J 2
(-485 2960);
DISPLAY 0.617021 (-485 2960);
PAINT ORANGE (-485 2960);
FORCEPROP 2 LASTPIN (-475 1700) $PN B35
J 2
(-485 1710);
DISPLAY 0.617021 (-485 1710);
PAINT ORANGE (-485 1710);
FORCEPROP 2 LASTPIN (-475 1350) $PN D35
J 2
(-485 1360);
DISPLAY 0.617021 (-485 1360);
PAINT ORANGE (-485 1360);
FORCEPROP 1 LAST LOCATION U7C1
J 0
(-380 3332);
DISPLAY 0.617021 (-380 3332);
PAINT AQUA (-380 3332);
FORCEPROP 1 LAST PART_NUMBER H91415-002
J 0
(-425 1100);
DISPLAY 0.617021 (-425 1100);
PAINT BLUE (-425 1100);
FORCEPROP 2 LASTPIN (-475 1900) $PN H17
J 2
(-485 1910);
DISPLAY 0.617021 (-485 1910);
PAINT ORANGE (-485 1910);
FORCEPROP 2 LASTPIN (-475 2400) $PN A39
J 2
(-485 2410);
DISPLAY 0.617021 (-485 2410);
PAINT ORANGE (-485 2410);
FORCEPROP 2 LASTPIN (1525 1400) $PN BV51
J 0
(1535 1410);
DISPLAY 0.617021 (1535 1410);
PAINT ORANGE (1535 1410);
FORCEPROP 2 LASTPIN (1525 2450) $PN G26
J 0
(1535 2460);
DISPLAY 0.617021 (1535 2460);
PAINT ORANGE (1535 2460);
FORCEPROP 2 LASTPIN (1525 3000) $PN K27
J 0
(1535 3010);
DISPLAY 0.617021 (1535 3010);
PAINT ORANGE (1535 3010);
FORCEPROP 2 LASTPIN (1525 3050) $PN H27
J 0
(1535 3060);
DISPLAY 0.617021 (1535 3060);
PAINT ORANGE (1535 3060);
FORCEPROP 2 LASTPIN (-475 2600) $PN B40
J 2
(-485 2610);
DISPLAY 0.617021 (-485 2610);
PAINT ORANGE (-485 2610);
FORCEPROP 2 LASTPIN (-475 3050) $PN A26
J 2
(-485 3060);
DISPLAY 0.617021 (-485 3060);
PAINT ORANGE (-485 3060);
FORCEPROP 2 LAST CDS_LIB mstr_u_proc
J 0
(525 2150);
PAINT ORANGE (525 2150);
DISPLAY INVISIBLE (525 2150);
FORCEPROP 1 LAST PATH I40
J 0
(525 3250);
PAINT GREEN (525 3250);
DISPLAY INVISIBLE (525 3250);
FORCEPROP 1 LAST PACK_TYPE BGA1
J 0
(-425 3350);
PAINT SKYBLUE (-425 3350);
DISPLAY INVISIBLE (-425 3350);
FORCEPROP 2 LAST CDS_LOCATION U7C1
J 0
(-380 3332);
DISPLAY 0.617021 (-380 3332);
PAINT AQUA (-380 3332);
DISPLAY INVISIBLE (-380 3332);
FORCEPROP 0 LAST BOM_COST SB
J 0
(-825 3800);
DISPLAY 1.361702 (-825 3800);
PAINT ORANGE (-825 3800);
DISPLAY INVISIBLE (-825 3800);
FORCEPROP 2 LAST SEC 1
J 0
(-375 3375);
DISPLAY 0.680851 (-375 3375);
PAINT MONO (-375 3375);
DISPLAY INVISIBLE (-375 3375);
FORCEPROP 2 LAST SEC_TYPE BGA1
J 0
(-375 3375);
DISPLAY 1.021277 (-375 3375);
PAINT ORANGE (-375 3375);
DISPLAY INVISIBLE (-375 3375);
FORCEPROP 0 LAST ROOM SB
J 0
(-825 3700);
DISPLAY 1.361702 (-825 3700);
PAINT ORANGE (-825 3700);
DISPLAY INVISIBLE (-825 3700);
FORCEADD OFFPAGE..2
R 2
(-2350 1350);
FORCEPROP 2 LAST $XR0 114 
J 0
(-2605 1350);
DISPLAY 0.638298 (-2605 1350);
PAINT MONO (-2605 1350);
FORCEPROP 2 LAST PATH I43
J 0
(-2300 1425);
DISPLAY 1.021277 (-2300 1425);
PAINT ORANGE (-2300 1425);
DISPLAY INVISIBLE (-2300 1425);
FORCEPROP 2 LAST CDS_LIB mstr_standard
J 0
(-2350 1350);
PAINT ORANGE (-2350 1350);
DISPLAY INVISIBLE (-2350 1350);
FORCEPROP 1 LAST OFFPAGE TRUE
J 2
(-2675 1225);
DISPLAY 0.872340 (-2675 1225);
PAINT GREEN (-2675 1225);
DISPLAY INVISIBLE (-2675 1225);
FORCEPROP 1 LAST COMMENT_BODY TRUE
J 2
(-2305 1255);
DISPLAY 0.872340 (-2305 1255);
PAINT PEACH (-2305 1255);
DISPLAY INVISIBLE (-2305 1255);
FORCEADD OFFPAGE..1
(-2350 1700);
FORCEPROP 2 LAST $XR0 114 
J 0
(-2602 1700);
DISPLAY 0.638298 (-2602 1700);
PAINT MONO (-2602 1700);
FORCEPROP 2 LAST PATH I45
J 0
(-2300 1775);
DISPLAY 1.021277 (-2300 1775);
PAINT ORANGE (-2300 1775);
DISPLAY INVISIBLE (-2300 1775);
FORCEPROP 2 LAST CDS_LIB mstr_standard
J 0
(-2350 1700);
PAINT ORANGE (-2350 1700);
DISPLAY INVISIBLE (-2350 1700);
FORCEPROP 1 LAST OFFPAGE TRUE
J 0
(-2025 1575);
DISPLAY 0.872340 (-2025 1575);
PAINT GREEN (-2025 1575);
DISPLAY INVISIBLE (-2025 1575);
FORCEPROP 1 LAST COMMENT_BODY TRUE
J 0
(-2225 1600);
DISPLAY 0.872340 (-2225 1600);
PAINT PEACH (-2225 1600);
DISPLAY INVISIBLE (-2225 1600);
FORCEADD CAP..1
(-1525 -200);
FORCEPROP 1 LASTPIN (-1525 -300) $PN 2
J 0
(-1515 -320);
DISPLAY 0.617021 (-1515 -320);
PAINT ORANGE (-1515 -320);
FORCEPROP 1 LAST MATERIAL COG
J 0
(-1475 -300);
DISPLAY 0.617021 (-1475 -300);
PAINT SKYBLUE (-1475 -300);
FORCEPROP 1 LAST TOLERANCE 5%
J 0
(-1475 -250);
DISPLAY 0.617021 (-1475 -250);
PAINT SKYBLUE (-1475 -250);
FORCEPROP 1 LASTPIN (-1525 -100) $PN 1
J 0
(-1515 -120);
DISPLAY 0.617021 (-1515 -120);
PAINT ORANGE (-1515 -120);
FORCEPROP 1 LAST LOCATION C7C5
J 0
(-1475 -100);
DISPLAY 0.617021 (-1475 -100);
PAINT AQUA (-1475 -100);
FORCEPROP 1 LAST PACK_TYPE 0402LF
J 0
(-1475 -400);
DISPLAY 0.617021 (-1475 -400);
PAINT SKYBLUE (-1475 -400);
FORCEPROP 0 LAST CONFIG 78.6R864.1FL
J 0
(-1475 -450);
DISPLAY 0.638298 (-1475 -450);
PAINT BROWN (-1475 -450);
DISPLAY BOTH (-1475 -450);
FORCEPROP 1 LAST PART_NUMBER A36095-047
J 0
(-1475 -350);
DISPLAY 0.617021 (-1475 -350);
PAINT BLUE (-1475 -350);
FORCEPROP 1 LAST VOLTAGE 50V
J 0
(-1475 -200);
DISPLAY 0.617021 (-1475 -200);
PAINT SKYBLUE (-1475 -200);
FORCEPROP 0 LAST NEW_VALUE 6.8PF
J 0
(-1475 -150);
DISPLAY 0.638298 (-1475 -150);
PAINT BROWN (-1475 -150);
DISPLAY BOTH (-1475 -150);
FORCEPROP 2 LAST CDS_LOCATION C7C5
J 0
(-1475 -100);
DISPLAY 0.617021 (-1475 -100);
PAINT AQUA (-1475 -100);
DISPLAY INVISIBLE (-1475 -100);
FORCEPROP 1 LAST PATH I47
J 0
(-1475 -50);
DISPLAY 0.978723 (-1475 -50);
PAINT WHITE (-1475 -50);
DISPLAY INVISIBLE (-1475 -50);
FORCEPROP 2 LAST BOM_COST SYS_CLOCK
J 0
(-1435 -90);
PAINT MONO (-1435 -90);
DISPLAY INVISIBLE (-1435 -90);
FORCEPROP 2 LAST CDS_LIB mstr_discrete
J 0
(-1525 -200);
PAINT ORANGE (-1525 -200);
DISPLAY INVISIBLE (-1525 -200);
FORCEPROP 2 LAST ROOM SB
J 0
(-1525 -200);
PAINT MONO (-1525 -200);
DISPLAY INVISIBLE (-1525 -200);
FORCEPROP 2 LAST SEC 1
J 0
(-1475 0);
DISPLAY 0.680851 (-1475 0);
PAINT MONO (-1475 0);
DISPLAY INVISIBLE (-1475 0);
FORCEPROP 2 LAST SEC_TYPE 0402LF
J 0
(-1475 0);
DISPLAY 1.021277 (-1475 0);
PAINT ORANGE (-1475 0);
DISPLAY INVISIBLE (-1475 0);
FORCEPROP 1 LAST VALUE 15.0PF
J 0
(-1475 -150);
DISPLAY 0.617021 (-1475 -150);
PAINT SKYBLUE (-1475 -150);
DISPLAY INVISIBLE (-1475 -150);
FORCEADD RES..1
(-1775 475);
FORCEPROP 1 LAST PART_NUMBER G22369-010
J 0
(-1825 575);
DISPLAY 0.617021 (-1825 575);
PAINT BLUE (-1825 575);
FORCEPROP 1 LASTPIN (-1675 475) $PN 2
J 0
(-1713 487);
DISPLAY 0.617021 (-1713 487);
PAINT ORANGE (-1713 487);
FORCEPROP 1 LASTPIN (-1875 475) $PN 1
J 0
(-1863 487);
DISPLAY 0.617021 (-1863 487);
PAINT ORANGE (-1863 487);
FORCEPROP 1 LAST PACK_TYPE 0603
J 0
(-1650 375);
DISPLAY 0.617021 (-1650 375);
PAINT SKYBLUE (-1650 375);
FORCEPROP 1 LAST LOCATION R7C1
J 0
(-1825 525);
DISPLAY 0.617021 (-1825 525);
PAINT AQUA (-1825 525);
FORCEPROP 1 LAST VALUE 200K
J 2
(-1800 375);
DISPLAY 0.617021 (-1800 375);
PAINT SKYBLUE (-1800 375);
FORCEPROP 1 LAST WATTAGE 1/10W
J 2
(-1800 325);
DISPLAY 0.617021 (-1800 325);
PAINT SKYBLUE (-1800 325);
FORCEPROP 1 LAST TOLERANCE 0.1%
J 0
(-1775 375);
DISPLAY 0.617021 (-1775 375);
PAINT SKYBLUE (-1775 375);
FORCEPROP 1 LAST MATERIAL CHIP
J 0
(-1775 325);
DISPLAY 0.617021 (-1775 325);
PAINT SKYBLUE (-1775 325);
FORCEPROP 2 LAST SEC_TYPE 0603
J 0
(-1825 675);
DISPLAY 1.021277 (-1825 675);
PAINT ORANGE (-1825 675);
DISPLAY INVISIBLE (-1825 675);
FORCEPROP 2 LAST SEC 1
J 0
(-1825 675);
DISPLAY 0.680851 (-1825 675);
PAINT MONO (-1825 675);
DISPLAY INVISIBLE (-1825 675);
FORCEPROP 2 LAST CDS_LOCATION R7C1
J 0
(-1825 525);
DISPLAY 0.617021 (-1825 525);
PAINT AQUA (-1825 525);
DISPLAY INVISIBLE (-1825 525);
FORCEPROP 1 LAST PATH I48
J 0
(-1825 625);
DISPLAY 0.978723 (-1825 625);
PAINT WHITE (-1825 625);
DISPLAY INVISIBLE (-1825 625);
FORCEPROP 2 LAST CDS_LIB mstr_discrete
J 0
(-1775 475);
PAINT ORANGE (-1775 475);
DISPLAY INVISIBLE (-1775 475);
FORCEPROP 2 LAST ROOM SB
J 0
(-1775 475);
PAINT MONO (-1775 475);
DISPLAY INVISIBLE (-1775 475);
FORCEADD CRYSTAL..1
(-1775 150);
FORCEPROP 1 LASTPIN (-1875 150) $PN 1
J 2
(-1830 160);
DISPLAY 0.617021 (-1830 160);
PAINT AQUA (-1830 160);
FORCEPROP 1 LAST LOCATION Y7C1
J 1
(-1770 249);
DISPLAY 0.617021 (-1770 249);
PAINT AQUA (-1770 249);
FORCEPROP 1 LAST VALUE 48.000MHZ
J 1
(-1768 211);
DISPLAY 0.617021 (-1768 211);
PAINT SKYBLUE (-1768 211);
FORCEPROP 1 LASTPIN (-1675 150) $PN 3
J 0
(-1710 160);
DISPLAY 0.617021 (-1710 160);
PAINT AQUA (-1710 160);
FORCEPROP 1 LAST MATERIAL IC
J 0
(-1786 66);
DISPLAY 0.617021 (-1786 66);
PAINT SKYBLUE (-1786 66);
FORCEPROP 1 LAST PART_NUMBER D71700-058
J 0
(-1975 0);
DISPLAY 0.617021 (-1975 0);
PAINT BLUE (-1975 0);
FORCEPROP 2 LAST CDS_LIB mstr_discrete
J 0
(-1775 150);
PAINT ORANGE (-1775 150);
DISPLAY INVISIBLE (-1775 150);
FORCEPROP 1 LAST PACK_TYPE 2013
J 0
(-1787 58);
DISPLAY 0.702128 (-1787 58);
PAINT SKYBLUE (-1787 58);
DISPLAY INVISIBLE (-1787 58);
FORCEPROP 2 LAST CDS_LOCATION Y7C1
J 1
(-1770 249);
DISPLAY 0.617021 (-1770 249);
PAINT AQUA (-1770 249);
DISPLAY INVISIBLE (-1770 249);
FORCEPROP 1 LAST PATH I49
J 0
(-1750 250);
DISPLAY 0.872340 (-1750 250);
PAINT PINK (-1750 250);
DISPLAY INVISIBLE (-1750 250);
FORCEPROP 2 LAST SEC_TYPE 2013
J 0
(-1750 300);
DISPLAY 1.021277 (-1750 300);
PAINT ORANGE (-1750 300);
DISPLAY INVISIBLE (-1750 300);
FORCEPROP 2 LAST SEC 1
J 0
(-1750 300);
PAINT MONO (-1750 300);
DISPLAY INVISIBLE (-1750 300);
FORCEPROP 0 LAST ROOM SB
J 0
(-1750 350);
DISPLAY 1.404255 (-1750 350);
PAINT ORANGE (-1750 350);
DISPLAY INVISIBLE (-1750 350);
FORCEADD CAP..1
(-2025 -200);
FORCEPROP 1 LAST MATERIAL COG
J 0
(-1975 -300);
DISPLAY 0.617021 (-1975 -300);
PAINT SKYBLUE (-1975 -300);
FORCEPROP 1 LASTPIN (-2025 -300) $PN 2
J 0
(-2015 -320);
DISPLAY 0.617021 (-2015 -320);
PAINT ORANGE (-2015 -320);
FORCEPROP 1 LAST TOLERANCE 5%
J 0
(-1975 -250);
DISPLAY 0.617021 (-1975 -250);
PAINT SKYBLUE (-1975 -250);
FORCEPROP 1 LASTPIN (-2025 -100) $PN 1
J 0
(-2015 -120);
DISPLAY 0.617021 (-2015 -120);
PAINT ORANGE (-2015 -120);
FORCEPROP 1 LAST LOCATION C7C4
J 0
(-1975 -100);
DISPLAY 0.617021 (-1975 -100);
PAINT AQUA (-1975 -100);
FORCEPROP 1 LAST PART_NUMBER A36095-047
J 0
(-1975 -350);
DISPLAY 0.617021 (-1975 -350);
PAINT BLUE (-1975 -350);
FORCEPROP 1 LAST PACK_TYPE 0402LF
J 0
(-1975 -400);
DISPLAY 0.617021 (-1975 -400);
PAINT SKYBLUE (-1975 -400);
FORCEPROP 0 LAST CONFIG 78.6R864.1FL
J 0
(-1975 -450);
DISPLAY 0.638298 (-1975 -450);
PAINT BROWN (-1975 -450);
DISPLAY BOTH (-1975 -450);
FORCEPROP 1 LAST VOLTAGE 50V
J 0
(-1975 -200);
DISPLAY 0.617021 (-1975 -200);
PAINT SKYBLUE (-1975 -200);
FORCEPROP 0 LAST NEW_VALUE 6.8PF
J 0
(-1975 -150);
DISPLAY 0.638298 (-1975 -150);
PAINT BROWN (-1975 -150);
DISPLAY BOTH (-1975 -150);
FORCEPROP 1 LAST PATH I50
J 0
(-1975 -50);
DISPLAY 0.978723 (-1975 -50);
PAINT WHITE (-1975 -50);
DISPLAY INVISIBLE (-1975 -50);
FORCEPROP 2 LAST SEC_TYPE 0402LF
J 0
(-1975 0);
DISPLAY 1.021277 (-1975 0);
PAINT ORANGE (-1975 0);
DISPLAY INVISIBLE (-1975 0);
FORCEPROP 2 LAST SEC 1
J 0
(-1975 0);
DISPLAY 0.680851 (-1975 0);
PAINT MONO (-1975 0);
DISPLAY INVISIBLE (-1975 0);
FORCEPROP 2 LAST CDS_LIB mstr_discrete
J 0
(-2025 -200);
PAINT ORANGE (-2025 -200);
DISPLAY INVISIBLE (-2025 -200);
FORCEPROP 2 LAST CDS_LOCATION C7C4
J 0
(-1975 -100);
DISPLAY 0.617021 (-1975 -100);
PAINT AQUA (-1975 -100);
DISPLAY INVISIBLE (-1975 -100);
FORCEPROP 2 LAST ROOM SB
J 0
(-2025 -200);
PAINT MONO (-2025 -200);
DISPLAY INVISIBLE (-2025 -200);
FORCEPROP 2 LAST BOM_COST SYS_CLOCK
J 0
(-1885 -390);
PAINT MONO (-1885 -390);
DISPLAY INVISIBLE (-1885 -390);
FORCEPROP 1 LAST VALUE 15.0PF
J 0
(-1975 -150);
DISPLAY 0.617021 (-1975 -150);
PAINT SKYBLUE (-1975 -150);
DISPLAY INVISIBLE (-1975 -150);
FORCEADD OFFPAGE..5
(-2575 625);
FORCEPROP 2 LAST $XR0 114 
J 0
(-2830 625);
DISPLAY 0.638298 (-2830 625);
PAINT MONO (-2830 625);
FORCEPROP 2 LAST PATH I51
J 0
(-2525 700);
DISPLAY 1.021277 (-2525 700);
PAINT ORANGE (-2525 700);
DISPLAY INVISIBLE (-2525 700);
FORCEPROP 2 LAST CDS_LIB mstr_standard
J 0
(-2575 625);
PAINT MONO (-2575 625);
DISPLAY INVISIBLE (-2575 625);
FORCEPROP 2 LAST BOM_COST SYS_CLOCK
J 0
(-2825 675);
PAINT MONO (-2825 675);
DISPLAY INVISIBLE (-2825 675);
FORCEPROP 1 LAST OFFPAGE TRUE
J 0
(-2255 495);
PAINT GREEN (-2255 495);
DISPLAY INVISIBLE (-2255 495);
FORCEPROP 1 LAST COMMENT_BODY TRUE
J 0
(-2475 545);
DISPLAY 1.148936 (-2475 545);
PAINT PEACH (-2475 545);
DISPLAY INVISIBLE (-2475 545);
FORCEADD GND..1
(-2025 -600);
FORCEPROP 3 LASTPIN (-2025 -550) SIG_NAME GND\g
J 0
(-2015 -540);
DISPLAY 0.659574 (-2015 -540);
PAINT MONO (-2015 -540);
DISPLAY INVISIBLE (-2015 -540);
FORCEPROP 2 LAST BOM_COST SYS_CLOCK
J 0
(-2325 -525);
PAINT MONO (-2325 -525);
DISPLAY INVISIBLE (-2325 -525);
FORCEPROP 1 LAST VOLTAGE 0
J 0
(-2025 -600);
DISPLAY 0.510638 (-2025 -600);
PAINT SKYBLUE (-2025 -600);
DISPLAY INVISIBLE (-2025 -600);
FORCEPROP 1 LAST SIZE 1B
J 0
(-1950 -650);
DISPLAY 0.872340 (-1950 -650);
PAINT GREEN (-1950 -650);
DISPLAY INVISIBLE (-1950 -650);
FORCEPROP 2 LAST CDS_LIB mstr_symbols
J 0
(-2025 -600);
PAINT ORANGE (-2025 -600);
DISPLAY INVISIBLE (-2025 -600);
FORCEPROP 1 LAST PATH I53
J 0
(-1950 -600);
DISPLAY 0.702128 (-1950 -600);
PAINT AQUA (-1950 -600);
DISPLAY INVISIBLE (-1950 -600);
FORCEPROP 1 LAST BODY_TYPE PLUMBING
J 0
(-2070 -643);
DISPLAY 0.340426 (-2070 -643);
PAINT GREEN (-2070 -643);
DISPLAY INVISIBLE (-2070 -643);
FORCEPROP 1 LAST HDL_POWER GND
J 0
(-2025 -450);
DISPLAY 0.702128 (-2025 -450);
PAINT GREEN (-2025 -450);
DISPLAY INVISIBLE (-2025 -450);
FORCEADD RES..1
(-25 475);
FORCEPROP 1 LASTPIN (75 475) $PN 2
J 0
(35 485);
DISPLAY 0.617021 (35 485);
PAINT WHITE (35 485);
FORCEPROP 1 LAST LOCATION R7C6
J 0
(-75 525);
DISPLAY 0.617021 (-75 525);
PAINT AQUA (-75 525);
FORCEPROP 1 LAST PART_NUMBER G22026-112
J 0
(-125 575);
DISPLAY 0.617021 (-125 575);
PAINT BLUE (-125 575);
FORCEPROP 1 LAST TOLERANCE 1.0%
J 0
(-25 420);
DISPLAY 0.617021 (-25 420);
PAINT SKYBLUE (-25 420);
FORCEPROP 1 LAST WATTAGE 1/10W
J 2
(70 375);
DISPLAY 0.617021 (70 375);
PAINT SKYBLUE (70 375);
FORCEPROP 1 LAST VALUE 10M
J 2
(-105 420);
DISPLAY 0.617021 (-105 420);
PAINT SKYBLUE (-105 420);
FORCEPROP 1 LAST MATERIAL CHIP
J 0
(-205 370);
DISPLAY 0.617021 (-205 370);
PAINT SKYBLUE (-205 370);
FORCEPROP 1 LASTPIN (-125 475) $PN 1
J 0
(-115 485);
DISPLAY 0.617021 (-115 485);
PAINT WHITE (-115 485);
FORCEPROP 1 LAST PACK_TYPE 0603
J 0
(75 420);
DISPLAY 0.617021 (75 420);
PAINT SKYBLUE (75 420);
FORCEPROP 2 LAST CDS_SEC 1
J 0
(-75 675);
DISPLAY 1.404255 (-75 675);
PAINT ORANGE (-75 675);
DISPLAY INVISIBLE (-75 675);
FORCEPROP 2 LAST $SEC 1
J 0
(-75 675);
DISPLAY 0.936170 (-75 675);
PAINT MONO (-75 675);
DISPLAY INVISIBLE (-75 675);
FORCEPROP 2 LAST CDS_LOCATION R7C6
J 0
(-75 525);
DISPLAY 0.617021 (-75 525);
PAINT AQUA (-75 525);
DISPLAY INVISIBLE (-75 525);
FORCEPROP 1 LAST PATH I54
J 0
(-75 625);
DISPLAY 0.978723 (-75 625);
PAINT WHITE (-75 625);
DISPLAY INVISIBLE (-75 625);
FORCEPROP 2 LAST CDS_LIB mstr_discrete
J 0
(-25 475);
DISPLAY 1.680851 (-25 475);
PAINT ORANGE (-25 475);
DISPLAY INVISIBLE (-25 475);
FORCEPROP 2 LAST ROOM SB
J 0
(-25 475);
PAINT MONO (-25 475);
DISPLAY INVISIBLE (-25 475);
FORCEPROP 2 LAST BOM_COST SYS_CLOCK
J 0
(-75 275);
PAINT MONO (-75 275);
DISPLAY INVISIBLE (-75 275);
FORCEADD CRYSTAL..1
(-25 125);
FORCEPROP 1 LAST PART_NUMBER C13544-023
J 0
(-200 -25);
DISPLAY 0.617021 (-200 -25);
PAINT BLUE (-200 -25);
FORCEPROP 1 LASTPIN (75 125) $PN 2
J 0
(40 135);
DISPLAY 0.617021 (40 135);
PAINT AQUA (40 135);
FORCEPROP 1 LAST LOCATION Y7C2
J 1
(-20 224);
DISPLAY 0.617021 (-20 224);
PAINT AQUA (-20 224);
FORCEPROP 1 LAST VALUE 32.768KHZ
J 1
(-18 186);
DISPLAY 0.617021 (-18 186);
PAINT SKYBLUE (-18 186);
FORCEPROP 1 LASTPIN (-125 125) $PN 1
J 2
(-80 135);
DISPLAY 0.617021 (-80 135);
PAINT AQUA (-80 135);
FORCEPROP 1 LAST MATERIAL IC
J 0
(-36 41);
DISPLAY 0.617021 (-36 41);
PAINT SKYBLUE (-36 41);
FORCEPROP 2 LAST SEC_TYPE SM
J 0
(0 275);
DISPLAY 1.021277 (0 275);
PAINT ORANGE (0 275);
DISPLAY INVISIBLE (0 275);
FORCEPROP 2 LAST SEC 1
J 0
(0 275);
PAINT MONO (0 275);
DISPLAY INVISIBLE (0 275);
FORCEPROP 1 LAST PATH I55
J 0
(0 225);
DISPLAY 0.872340 (0 225);
PAINT PINK (0 225);
DISPLAY INVISIBLE (0 225);
FORCEPROP 2 LAST ROOM SB
J 0
(0 350);
DISPLAY 1.404255 (0 350);
PAINT ORANGE (0 350);
DISPLAY INVISIBLE (0 350);
FORCEPROP 2 LAST CDS_LOCATION Y7C2
J 1
(-20 224);
DISPLAY 0.617021 (-20 224);
PAINT AQUA (-20 224);
DISPLAY INVISIBLE (-20 224);
FORCEPROP 2 LAST CDS_LIB mstr_discrete
J 0
(-25 125);
PAINT ORANGE (-25 125);
DISPLAY INVISIBLE (-25 125);
FORCEPROP 1 LAST PACK_TYPE SM
J 0
(-37 33);
DISPLAY 0.702128 (-37 33);
PAINT SKYBLUE (-37 33);
DISPLAY INVISIBLE (-37 33);
FORCEADD GND..1
(-275 -575);
FORCEPROP 3 LASTPIN (-275 -525) SIG_NAME GND\g
J 0
(-265 -515);
DISPLAY 0.659574 (-265 -515);
PAINT MONO (-265 -515);
DISPLAY INVISIBLE (-265 -515);
FORCEPROP 1 LAST VOLTAGE 0
J 0
(-275 -575);
DISPLAY 0.510638 (-275 -575);
PAINT SKYBLUE (-275 -575);
DISPLAY INVISIBLE (-275 -575);
FORCEPROP 1 LAST SIZE 1B
J 0
(-200 -625);
DISPLAY 0.872340 (-200 -625);
PAINT GREEN (-200 -625);
DISPLAY INVISIBLE (-200 -625);
FORCEPROP 2 LAST CDS_LIB mstr_symbols
J 0
(-275 -575);
PAINT ORANGE (-275 -575);
DISPLAY INVISIBLE (-275 -575);
FORCEPROP 1 LAST PATH I57
J 0
(-200 -575);
DISPLAY 0.872340 (-200 -575);
PAINT AQUA (-200 -575);
DISPLAY INVISIBLE (-200 -575);
FORCEPROP 2 LAST BOM_COST SYS_CLOCK
J 0
(-575 -500);
PAINT MONO (-575 -500);
DISPLAY INVISIBLE (-575 -500);
FORCEPROP 1 LAST BODY_TYPE PLUMBING
J 0
(-320 -618);
DISPLAY 0.340426 (-320 -618);
PAINT GREEN (-320 -618);
DISPLAY INVISIBLE (-320 -618);
FORCEPROP 1 LAST HDL_POWER GND
J 0
(-275 -425);
DISPLAY 0.702128 (-275 -425);
PAINT GREEN (-275 -425);
DISPLAY INVISIBLE (-275 -425);
FORCEADD OFFPAGE..4
R 2
(-925 725);
FORCEPROP 2 LAST $XR0 114 
J 0
(-1177 725);
DISPLAY 0.638298 (-1177 725);
PAINT MONO (-1177 725);
FORCEPROP 2 LAST PATH I58
J 0
(-875 800);
DISPLAY 1.021277 (-875 800);
PAINT ORANGE (-875 800);
DISPLAY INVISIBLE (-875 800);
FORCEPROP 2 LAST CDS_LIB mstr_standard
J 0
(-925 725);
PAINT ORANGE (-925 725);
DISPLAY INVISIBLE (-925 725);
FORCEPROP 2 LAST BOM_COST SYS_CLOCK
J 0
(-1200 775);
PAINT MONO (-1200 775);
DISPLAY INVISIBLE (-1200 775);
FORCEPROP 1 LAST OFFPAGE TRUE
J 2
(-1250 600);
PAINT GREEN (-1250 600);
DISPLAY INVISIBLE (-1250 600);
FORCEPROP 1 LAST COMMENT_BODY TRUE
J 2
(-900 625);
DISPLAY 1.212766 (-900 625);
PAINT PEACH (-900 625);
DISPLAY INVISIBLE (-900 625);
FORCEADD OFFPAGE..5
(-925 625);
FORCEPROP 2 LAST $XR0 114 
J 0
(-1180 625);
DISPLAY 0.638298 (-1180 625);
PAINT MONO (-1180 625);
FORCEPROP 2 LAST PATH I59
J 0
(-875 700);
DISPLAY 1.021277 (-875 700);
PAINT ORANGE (-875 700);
DISPLAY INVISIBLE (-875 700);
FORCEPROP 2 LAST CDS_LIB mstr_standard
J 0
(-925 625);
PAINT ORANGE (-925 625);
DISPLAY INVISIBLE (-925 625);
FORCEPROP 2 LAST BOM_COST SYS_CLOCK
J 0
(-1175 675);
PAINT MONO (-1175 675);
DISPLAY INVISIBLE (-1175 675);
FORCEPROP 1 LAST OFFPAGE TRUE
J 0
(-605 495);
PAINT GREEN (-605 495);
DISPLAY INVISIBLE (-605 495);
FORCEPROP 1 LAST COMMENT_BODY TRUE
J 0
(-825 545);
DISPLAY 1.148936 (-825 545);
PAINT PEACH (-825 545);
DISPLAY INVISIBLE (-825 545);
FORCEADD OFFPAGE..4
R 2
(-2575 725);
FORCEPROP 2 LAST $XR0 114 
J 0
(-2827 725);
DISPLAY 0.638298 (-2827 725);
PAINT MONO (-2827 725);
FORCEPROP 2 LAST PATH I60
J 0
(-2525 800);
DISPLAY 1.021277 (-2525 800);
PAINT ORANGE (-2525 800);
DISPLAY INVISIBLE (-2525 800);
FORCEPROP 2 LAST CDS_LIB mstr_standard
J 0
(-2575 725);
PAINT MONO (-2575 725);
DISPLAY INVISIBLE (-2575 725);
FORCEPROP 2 LAST BOM_COST SYS_CLOCK
J 0
(-2850 775);
PAINT MONO (-2850 775);
DISPLAY INVISIBLE (-2850 775);
FORCEPROP 1 LAST OFFPAGE TRUE
J 2
(-2900 600);
PAINT GREEN (-2900 600);
DISPLAY INVISIBLE (-2900 600);
FORCEPROP 1 LAST COMMENT_BODY TRUE
J 2
(-2550 625);
DISPLAY 1.212766 (-2550 625);
PAINT PEACH (-2550 625);
DISPLAY INVISIBLE (-2550 625);
FORCEADD OFFPAGE..2
(3700 1350);
FORCEPROP 2 LAST $XR1 55 
J 0
(3979 1350);
DISPLAY 0.638298 (3979 1350);
PAINT MONO (3979 1350);
FORCEPROP 2 LAST $XR0 21 
J 0
(3889 1350);
DISPLAY 0.638298 (3889 1350);
PAINT MONO (3889 1350);
FORCEPROP 2 LAST PATH I62
J 0
(3875 1425);
DISPLAY 1.021277 (3875 1425);
PAINT ORANGE (3875 1425);
DISPLAY INVISIBLE (3875 1425);
FORCEPROP 2 LAST CDS_LIB mstr_standard
J 0
(3700 1350);
PAINT ORANGE (3700 1350);
DISPLAY INVISIBLE (3700 1350);
FORCEPROP 1 LAST OFFPAGE TRUE
J 0
(4025 1225);
DISPLAY 0.872340 (4025 1225);
PAINT GREEN (4025 1225);
DISPLAY INVISIBLE (4025 1225);
FORCEPROP 1 LAST COMMENT_BODY TRUE
J 0
(3655 1255);
DISPLAY 0.872340 (3655 1255);
PAINT PEACH (3655 1255);
DISPLAY INVISIBLE (3655 1255);
FORCEADD OFFPAGE..2
(3700 550);
FORCEPROP 2 LASTPIN (3650 550) SIG_NAME CLK_48M_USB_BMC
J 2
(3640 560);
DISPLAY 0.617021 (3640 560);
PAINT ORANGE (3640 560);
FORCEPROP 2 LAST $XR0 144 
J 0
(3889 550);
DISPLAY 0.638298 (3889 550);
PAINT MONO (3889 550);
FORCEPROP 2 LAST PATH I63
J 0
(3875 625);
DISPLAY 1.021277 (3875 625);
PAINT ORANGE (3875 625);
DISPLAY INVISIBLE (3875 625);
FORCEPROP 2 LAST CDS_LIB mstr_standard
J 0
(3700 550);
PAINT ORANGE (3700 550);
DISPLAY INVISIBLE (3700 550);
FORCEPROP 1 LAST OFFPAGE TRUE
J 0
(4025 425);
DISPLAY 0.872340 (4025 425);
PAINT GREEN (4025 425);
DISPLAY INVISIBLE (4025 425);
FORCEPROP 1 LAST COMMENT_BODY TRUE
J 0
(3655 455);
DISPLAY 0.872340 (3655 455);
PAINT PEACH (3655 455);
DISPLAY INVISIBLE (3655 455);
FORCEADD OFFPAGE..2
R 2
(-2350 1900);
FORCEPROP 2 LAST $XR0 114 
J 0
(-2605 1900);
DISPLAY 0.638298 (-2605 1900);
PAINT MONO (-2605 1900);
FORCEPROP 2 LAST PATH I64
J 0
(-2300 1975);
DISPLAY 1.021277 (-2300 1975);
PAINT ORANGE (-2300 1975);
DISPLAY INVISIBLE (-2300 1975);
FORCEPROP 2 LAST CDS_LIB mstr_standard
J 0
(-2350 1900);
PAINT ORANGE (-2350 1900);
DISPLAY INVISIBLE (-2350 1900);
FORCEPROP 1 LAST OFFPAGE TRUE
J 2
(-2675 1775);
DISPLAY 0.872340 (-2675 1775);
PAINT GREEN (-2675 1775);
DISPLAY INVISIBLE (-2675 1775);
FORCEPROP 1 LAST COMMENT_BODY TRUE
J 2
(-2305 1805);
DISPLAY 0.872340 (-2305 1805);
PAINT PEACH (-2305 1805);
DISPLAY INVISIBLE (-2305 1805);
FORCEADD OFFPAGE..2
(3700 1850);
FORCEPROP 2 LAST $XR0 108 
J 0
(3889 1850);
DISPLAY 0.638298 (3889 1850);
PAINT MONO (3889 1850);
FORCEPROP 2 LAST PATH I89
J 0
(3875 1925);
DISPLAY 1.021277 (3875 1925);
PAINT ORANGE (3875 1925);
DISPLAY INVISIBLE (3875 1925);
FORCEPROP 2 LAST CDS_LIB mstr_standard
J 0
(3700 1850);
PAINT ORANGE (3700 1850);
DISPLAY INVISIBLE (3700 1850);
FORCEPROP 1 LAST OFFPAGE TRUE
J 0
(4025 1725);
DISPLAY 0.872340 (4025 1725);
PAINT GREEN (4025 1725);
DISPLAY INVISIBLE (4025 1725);
FORCEPROP 1 LAST COMMENT_BODY TRUE
J 0
(3655 1755);
DISPLAY 0.872340 (3655 1755);
PAINT PEACH (3655 1755);
DISPLAY INVISIBLE (3655 1755);
FORCEADD OFFPAGE..2
(3700 1800);
FORCEPROP 2 LAST $XR0 108 
J 0
(3889 1800);
DISPLAY 0.638298 (3889 1800);
PAINT MONO (3889 1800);
FORCEPROP 2 LAST PATH I90
J 0
(3875 1875);
DISPLAY 1.021277 (3875 1875);
PAINT ORANGE (3875 1875);
DISPLAY INVISIBLE (3875 1875);
FORCEPROP 2 LAST CDS_LIB mstr_standard
J 0
(3700 1800);
PAINT ORANGE (3700 1800);
DISPLAY INVISIBLE (3700 1800);
FORCEPROP 1 LAST OFFPAGE TRUE
J 0
(4025 1675);
DISPLAY 0.872340 (4025 1675);
PAINT GREEN (4025 1675);
DISPLAY INVISIBLE (4025 1675);
FORCEPROP 1 LAST COMMENT_BODY TRUE
J 0
(3655 1705);
DISPLAY 0.872340 (3655 1705);
PAINT PEACH (3655 1705);
DISPLAY INVISIBLE (3655 1705);
FORCEADD OFFPAGE..2
(3700 2050);
FORCEPROP 2 LAST $XR0 108 
J 0
(3889 2050);
DISPLAY 0.638298 (3889 2050);
PAINT MONO (3889 2050);
FORCEPROP 2 LAST PATH I93
J 0
(3875 2125);
DISPLAY 1.021277 (3875 2125);
PAINT ORANGE (3875 2125);
DISPLAY INVISIBLE (3875 2125);
FORCEPROP 2 LAST CDS_LIB mstr_standard
J 0
(3700 2050);
PAINT ORANGE (3700 2050);
DISPLAY INVISIBLE (3700 2050);
FORCEPROP 1 LAST OFFPAGE TRUE
J 0
(4025 1925);
DISPLAY 0.872340 (4025 1925);
PAINT GREEN (4025 1925);
DISPLAY INVISIBLE (4025 1925);
FORCEPROP 1 LAST COMMENT_BODY TRUE
J 0
(3655 1955);
DISPLAY 0.872340 (3655 1955);
PAINT PEACH (3655 1955);
DISPLAY INVISIBLE (3655 1955);
FORCEADD OFFPAGE..2
(3700 2000);
FORCEPROP 2 LAST $XR0 108 
J 0
(3889 2000);
DISPLAY 0.638298 (3889 2000);
PAINT MONO (3889 2000);
FORCEPROP 2 LAST PATH I94
J 0
(3875 2075);
DISPLAY 1.021277 (3875 2075);
PAINT ORANGE (3875 2075);
DISPLAY INVISIBLE (3875 2075);
FORCEPROP 2 LAST CDS_LIB mstr_standard
J 0
(3700 2000);
PAINT ORANGE (3700 2000);
DISPLAY INVISIBLE (3700 2000);
FORCEPROP 1 LAST OFFPAGE TRUE
J 0
(4025 1875);
DISPLAY 0.872340 (4025 1875);
PAINT GREEN (4025 1875);
DISPLAY INVISIBLE (4025 1875);
FORCEPROP 1 LAST COMMENT_BODY TRUE
J 0
(3655 1905);
DISPLAY 0.872340 (3655 1905);
PAINT PEACH (3655 1905);
DISPLAY INVISIBLE (3655 1905);
FORCEADD OFFPAGE..2
(3700 2150);
FORCEPROP 2 LAST $XR0 108 
J 0
(3889 2150);
DISPLAY 0.638298 (3889 2150);
PAINT MONO (3889 2150);
FORCEPROP 2 LAST PATH I95
J 0
(3875 2225);
DISPLAY 1.021277 (3875 2225);
PAINT ORANGE (3875 2225);
DISPLAY INVISIBLE (3875 2225);
FORCEPROP 2 LAST CDS_LIB mstr_standard
J 0
(3700 2150);
PAINT ORANGE (3700 2150);
DISPLAY INVISIBLE (3700 2150);
FORCEPROP 1 LAST OFFPAGE TRUE
J 0
(4025 2025);
DISPLAY 0.872340 (4025 2025);
PAINT GREEN (4025 2025);
DISPLAY INVISIBLE (4025 2025);
FORCEPROP 1 LAST COMMENT_BODY TRUE
J 0
(3655 2055);
DISPLAY 0.872340 (3655 2055);
PAINT PEACH (3655 2055);
DISPLAY INVISIBLE (3655 2055);
FORCEADD OFFPAGE..2
(3700 2100);
FORCEPROP 2 LAST $XR0 108 
J 0
(3889 2100);
DISPLAY 0.638298 (3889 2100);
PAINT MONO (3889 2100);
FORCEPROP 2 LAST PATH I96
J 0
(3875 2175);
DISPLAY 1.021277 (3875 2175);
PAINT ORANGE (3875 2175);
DISPLAY INVISIBLE (3875 2175);
FORCEPROP 2 LAST CDS_LIB mstr_standard
J 0
(3700 2100);
PAINT ORANGE (3700 2100);
DISPLAY INVISIBLE (3700 2100);
FORCEPROP 1 LAST OFFPAGE TRUE
J 0
(4025 1975);
DISPLAY 0.872340 (4025 1975);
PAINT GREEN (4025 1975);
DISPLAY INVISIBLE (4025 1975);
FORCEPROP 1 LAST COMMENT_BODY TRUE
J 0
(3655 2005);
DISPLAY 0.872340 (3655 2005);
PAINT PEACH (3655 2005);
DISPLAY INVISIBLE (3655 2005);
FORCEADD CAD_NOTE..1
(-2875 3200);
FORCEPROP 0 LAST L1 PLACE BIAS RESISTOR WITHIN 1 INCH OF PCH
J 0
(-3025 3100);
DISPLAY 0.808511 (-3025 3100);
PAINT WHITE (-3025 3100);
FORCEPROP 2 LAST CDS_LIB mstr_symbols
J 0
(-2875 3200);
PAINT ORANGE (-2875 3200);
DISPLAY INVISIBLE (-2875 3200);
FORCEPROP 1 LAST COMMENT_BODY TRUE
J 0
(-2850 3300);
DISPLAY 0.978723 (-2850 3300);
PAINT PEACH (-2850 3300);
DISPLAY INVISIBLE (-2850 3300);
FORCEADD CAD_NOTE..1
(-1000 -850);
FORCEPROP 0 LAST L1 PLACE ON TOP LAYER ONLY
J 0
(-1150 -975);
DISPLAY 0.936170 (-1150 -975);
PAINT WHITE (-1150 -975);
FORCEPROP 2 LAST CDS_LIB mstr_symbols
J 0
(-1000 -850);
PAINT ORANGE (-1000 -850);
DISPLAY INVISIBLE (-1000 -850);
FORCEPROP 1 LAST COMMENT_BODY TRUE
J 0
(-975 -750);
DISPLAY 1.595745 (-975 -750);
PAINT PEACH (-975 -750);
DISPLAY INVISIBLE (-975 -750);
FORCEADD DESIGN_NOTE..1
(525 475);
FORCEPROP 0 LAST L2 AND VALUE.
J 0
(400 300);
DISPLAY 0.617021 (400 300);
PAINT WHITE (400 300);
FORCEPROP 0 LAST L3 * CAP VALUE MAY NEED TUNING.
J 0
(325 225);
DISPLAY 0.617021 (325 225);
PAINT WHITE (325 225);
FORCEPROP 0 LAST L1 * NC RECOMMENDED COMPONENTS
J 0
(325 350);
DISPLAY 0.617021 (325 350);
PAINT WHITE (325 350);
FORCEPROP 2 LAST CDS_LIB mstr_symbols
J 0
(525 475);
PAINT WHITE (525 475);
DISPLAY INVISIBLE (525 475);
FORCEPROP 2 LAST BOM_COST SM_CONTROLLER
J 0
(325 425);
PAINT WHITE (325 425);
DISPLAY INVISIBLE (325 425);
FORCEPROP 2 LAST ROOM BMC
J 0
(325 425);
PAINT WHITE (325 425);
DISPLAY INVISIBLE (325 425);
FORCEPROP 1 LAST COMMENT_BODY TRUE
J 0
(550 575);
DISPLAY 1.319149 (550 575);
PAINT PEACH (550 575);
DISPLAY INVISIBLE (550 575);
FORCEADD DNS..2
(-2845 2745);
PAINT RED (-2845 2745);
FORCEPROP 2 LAST CDS_LIB mstr_misc
J 0
(-2845 2745);
PAINT MONO (-2845 2745);
DISPLAY INVISIBLE (-2845 2745);
FORCEPROP 1 LAST COMMENT_BODY TRUE
R 1
J 0
(-2770 2520);
DISPLAY 0.872340 (-2770 2520);
PAINT GREEN (-2770 2520);
DISPLAY INVISIBLE (-2770 2520);
FORCEADD DESIGN_NOTE..1
(-1125 325);
FORCEPROP 0 LAST L2 200 KOHM AND 10 MOHM RESISTORS.
J 0
(-1325 150);
DISPLAY 0.617021 (-1325 150);
PAINT WHITE (-1325 150);
FORCEPROP 0 LAST L1 MANTAIN 0603 PACKAGE FOR
J 0
(-1325 200);
DISPLAY 0.617021 (-1325 200);
PAINT WHITE (-1325 200);
FORCEPROP 2 LAST CDS_LIB mstr_symbols
J 0
(-1125 325);
PAINT WHITE (-1125 325);
DISPLAY INVISIBLE (-1125 325);
FORCEPROP 2 LAST ROOM BMC
J 0
(-1325 275);
PAINT WHITE (-1325 275);
DISPLAY INVISIBLE (-1325 275);
FORCEPROP 2 LAST BOM_COST SM_CONTROLLER
J 0
(-1325 275);
PAINT WHITE (-1325 275);
DISPLAY INVISIBLE (-1325 275);
FORCEPROP 1 LAST COMMENT_BODY TRUE
J 0
(-1100 425);
DISPLAY 1.319149 (-1100 425);
PAINT PEACH (-1100 425);
DISPLAY INVISIBLE (-1100 425);
FORCEADD INTEL_CORP_BPAGE..1
(4775 -1050);
FORCEPROP 1 LAST CDS_CON_LAST_MODIFIED Fri Jun 16 17:48:45 2017
J 0
(3350 -725);
PAINT ORANGE (3350 -725);
DISPLAY INVISIBLE (3350 -725);
FORCEPROP 1 LAST CUSTOM_TXT_CDS <CURRENT_DESIGN_SHEET> OF <TOTAL_DESIGN_SHEETS>
J 0
(4275 -1025);
PAINT ORANGE (4275 -1025);
FORCEPROP 1 LAST CUSTOM_TXT_CDS <CON_LAST_MODIFIED>
J 0
(775 -950);
PAINT ORANGE (775 -950);
FORCEPROP 2 LAST CUSTOM_TXT_CDS <XR_PAGE_TITLE>
J 0
(-3115 4200);
DISPLAY 0.638298 (-3115 4200);
PAINT PINK (-3115 4200);
DISPLAY INVISIBLE (-3115 4200);
FORCEPROP 1 LAST SCH_TITLE LEWISBURG 1/11 CLOCKS
J 0
(-3175 -1000);
DISPLAY 1.212766 (-3175 -1000);
PAINT YELLOW (-3175 -1000);
FORCEPROP 2 LAST CDS_LIB mstr_symbols
J 0
(4775 -1050);
PAINT ORANGE (4775 -1050);
DISPLAY INVISIBLE (4775 -1050);
FORCEPROP 2 LAST PAGE_BORDER TRUE
J 0
(-3115 4200);
DISPLAY 0.638298 (-3115 4200);
PAINT PINK (-3115 4200);
DISPLAY INVISIBLE (-3115 4200);
FORCEPROP 1 LAST COMMENT_BODY TRUE
J 0
(4787 -1038);
DISPLAY 0.468085 (4787 -1038);
PAINT PEACH (4787 -1038);
DISPLAY INVISIBLE (4787 -1038);
FORCEPROP 2 LAST CDS_XR_PAGE_TITLE CR-114 : @BASEBOARD_FAB2_LIB.BASEBOARD_FAB2(SCH_1):PAGE114
J 0
(-3115 4200);
DISPLAY 0.638298 (-3115 4200);
PAINT PINK (-3115 4200);
DISPLAY INVISIBLE (-3115 4200);
FORCEADD DNS..2
(2905 1095);
PAINT RED (2905 1095);
FORCEPROP 2 LAST CDS_LIB mstr_misc
J 0
(2905 1095);
PAINT ORANGE (2905 1095);
DISPLAY INVISIBLE (2905 1095);
FORCEPROP 1 LAST COMMENT_BODY TRUE
R 1
J 0
(2980 870);
DISPLAY 0.872340 (2980 870);
PAINT GREEN (2980 870);
DISPLAY INVISIBLE (2980 870);
FORCEADD DESIGN_NOTE..1
(-2675 325);
FORCEPROP 0 LAST L2 AND VALUE.
J 0
(-2800 150);
DISPLAY 0.617021 (-2800 150);
PAINT WHITE (-2800 150);
FORCEPROP 0 LAST L1 * NC RECOMMENDED COMPONENTS
J 0
(-2875 200);
DISPLAY 0.617021 (-2875 200);
PAINT WHITE (-2875 200);
FORCEPROP 0 LAST L3 * CAP VALUE MAY NEED TUNING.
J 0
(-2875 75);
DISPLAY 0.617021 (-2875 75);
PAINT WHITE (-2875 75);
FORCEPROP 2 LAST BOM_COST SM_CONTROLLER
J 0
(-2875 275);
PAINT WHITE (-2875 275);
DISPLAY INVISIBLE (-2875 275);
FORCEPROP 2 LAST CDS_LIB mstr_symbols
J 0
(-2675 325);
PAINT MONO (-2675 325);
DISPLAY INVISIBLE (-2675 325);
FORCEPROP 2 LAST ROOM BMC
J 0
(-2875 275);
PAINT WHITE (-2875 275);
DISPLAY INVISIBLE (-2875 275);
FORCEPROP 1 LAST COMMENT_BODY TRUE
J 0
(-2650 425);
DISPLAY 1.319149 (-2650 425);
PAINT PEACH (-2650 425);
DISPLAY INVISIBLE (-2650 425);
WIRE 16 -1 (2900 900)(2900 1000);
WIRE 16 -1 (-3150 2650)(-3150 2550);
WIRE 16 -1 (-2850 2650)(-2850 2550);
WIRE 16 -1 (-2025 -550)(-2025 -500);
WIRE 16 -1 (-1525 -500)(-2025 -500);
WIRE 16 -1 (-2025 -300)(-2025 -500);
WIRE 16 -1 (-1525 -500)(-1525 -300);
WIRE 16 -1 (-275 -525)(-275 -475);
WIRE 16 -1 (225 -475)(-275 -475);
WIRE 16 -1 (-275 -325)(-275 -475);
WIRE 16 -1 (225 -325)(225 -475);
WIRE 16 -1 (-2300 2450)(-475 2450);
FORCEPROP 0 LAST SIG_NAME CLK_100M_PCH_XDP_DP
J 0
(-2300 2451);
DISPLAY 0.617021 (-2300 2451);
PAINT ORANGE (-2300 2451);
WIRE 16 -1 (3650 2200)(1525 2200);
FORCEPROP 0 LAST SIG_NAME CLK_100M_PCH_SLOTX24_S5_DN
J 0
(3020 2210);
DISPLAY 0.617021 (3020 2210);
PAINT ORANGE (3020 2210);
WIRE 16 -1 (3650 1550)(1525 1550);
FORCEPROP 0 LAST SIG_NAME CLK_100M_AIRMAX8_PE1_DP
J 0
(3020 1560);
DISPLAY 0.617021 (3020 1560);
PAINT ORANGE (3020 1560);
WIRE 16 -1 (1525 3050)(3650 3050);
FORCEPROP 2 LAST SIG_NAME CLK_100M_M2_DP
J 0
(3015 3060);
DISPLAY 0.617021 (3015 3060);
PAINT ORANGE (3015 3060);
WIRE 16 -1 (1525 3000)(3650 3000);
FORCEPROP 0 LAST SIG_NAME CLK_100M_M2_DN
J 0
(3015 3010);
DISPLAY 0.617021 (3015 3010);
PAINT ORANGE (3015 3010);
WIRE 16 -1 (1525 2950)(3650 2950);
FORCEPROP 2 LAST SIG_NAME CLK_100M_SPRV_DP
J 0
(3015 2960);
DISPLAY 0.617021 (3015 2960);
PAINT ORANGE (3015 2960);
WIRE 16 -1 (1525 2900)(3650 2900);
FORCEPROP 2 LAST SIG_NAME CLK_100M_SPRV_DN
J 0
(3015 2910);
DISPLAY 0.617021 (3015 2910);
PAINT ORANGE (3015 2910);
WIRE 16 -1 (3650 2650)(1525 2650);
FORCEPROP 0 LAST SIG_NAME CLK_100M_MEZZ4_DP
J 0
(3020 2660);
DISPLAY 0.617021 (3020 2660);
PAINT ORANGE (3020 2660);
WIRE 16 -1 (3650 2600)(1525 2600);
FORCEPROP 0 LAST SIG_NAME CLK_100M_MEZZ4_DN
J 0
(3020 2610);
DISPLAY 0.617021 (3020 2610);
PAINT ORANGE (3020 2610);
WIRE 16 -1 (3650 2550)(1525 2550);
FORCEPROP 0 LAST SIG_NAME CLK_100M_MEZZ3_DP
J 0
(3020 2560);
DISPLAY 0.617021 (3020 2560);
PAINT ORANGE (3020 2560);
WIRE 16 -1 (3650 2300)(1525 2300);
FORCEPROP 0 LAST SIG_NAME CLK_100M_MEZZ1_DN
J 0
(3020 2310);
DISPLAY 0.617021 (3020 2310);
PAINT ORANGE (3020 2310);
WIRE 3 682 (1700 2700)(1750 2700);
WIRE 3 682 (1650 2700)(1700 2700);
WIRE 3 682 (1650 2850)(1700 2850);
WIRE 3 682 (1700 2850)(1700 2700);
WIRE 16 -1 (3650 2500)(1525 2500);
FORCEPROP 0 LAST SIG_NAME CLK_100M_MEZZ3_DN
J 0
(3020 2510);
DISPLAY 0.617021 (3020 2510);
PAINT ORANGE (3020 2510);
WIRE 16 -1 (3650 2450)(1525 2450);
FORCEPROP 0 LAST SIG_NAME CLK_100M_MEZZ2_DP
J 0
(3020 2460);
DISPLAY 0.617021 (3020 2460);
PAINT ORANGE (3020 2460);
WIRE 16 -1 (3650 2400)(1525 2400);
FORCEPROP 0 LAST SIG_NAME CLK_100M_MEZZ2_DN
J 0
(3020 2410);
DISPLAY 0.617021 (3020 2410);
PAINT ORANGE (3020 2410);
WIRE 16 -1 (3650 2100)(1525 2100);
FORCEPROP 0 LAST SIG_NAME CLK_100M_PCH_SLOTX24_S4_DN
J 0
(3020 2110);
DISPLAY 0.617021 (3020 2110);
PAINT ORANGE (3020 2110);
WIRE 16 -1 (3650 2250)(1525 2250);
FORCEPROP 0 LAST SIG_NAME CLK_100M_PCH_SLOTX24_S5_DP
J 0
(3020 2260);
DISPLAY 0.617021 (3020 2260);
PAINT ORANGE (3020 2260);
WIRE 16 -1 (3650 2350)(1525 2350);
FORCEPROP 0 LAST SIG_NAME CLK_100M_MEZZ1_DP
J 0
(3020 2360);
DISPLAY 0.617021 (3020 2360);
PAINT ORANGE (3020 2360);
WIRE 16 -1 (2900 1350)(2400 1350);
WIRE 16 -1 (2900 1350)(2900 1200);
WIRE 16 -1 (3650 1350)(2900 1350);
FORCEPROP 0 LAST SIG_NAME H_PMSYNC_CLK_24M
J 0
(3215 1360);
DISPLAY 0.617021 (3215 1360);
PAINT ORANGE (3215 1360);
WIRE 16 -1 (3650 1650)(1525 1650);
FORCEPROP 0 LAST SIG_NAME CLK_100M_DB1200_DP
J 0
(3020 1660);
DISPLAY 0.617021 (3020 1660);
PAINT ORANGE (3020 1660);
WIRE 16 -1 (3650 1750)(1525 1750);
FORCEPROP 0 LAST SIG_NAME CLK_100M_PCH_SLOTX24_S0_DP
J 0
(3020 1760);
DISPLAY 0.617021 (3020 1760);
PAINT ORANGE (3020 1760);
WIRE 16 -1 (3650 2000)(1525 2000);
FORCEPROP 0 LAST SIG_NAME CLK_100M_PCH_SLOTX24_S3_DN
J 0
(3020 2010);
DISPLAY 0.617021 (3020 2010);
PAINT ORANGE (3020 2010);
WIRE 16 -1 (3650 1850)(1525 1850);
FORCEPROP 0 LAST SIG_NAME CLK_100M_PCH_SLOTX24_S1_DP
J 0
(3020 1860);
DISPLAY 0.617021 (3020 1860);
PAINT ORANGE (3020 1860);
WIRE 16 -1 (3650 1900)(1525 1900);
FORCEPROP 0 LAST SIG_NAME CLK_100M_PCH_SLOTX24_S2_DN
J 0
(3020 1910);
DISPLAY 0.617021 (3020 1910);
PAINT ORANGE (3020 1910);
WIRE 16 -1 (3650 2150)(1525 2150);
FORCEPROP 0 LAST SIG_NAME CLK_100M_PCH_SLOTX24_S4_DP
J 0
(3020 2160);
DISPLAY 0.617021 (3020 2160);
PAINT ORANGE (3020 2160);
WIRE 16 -1 (3650 1950)(1525 1950);
FORCEPROP 0 LAST SIG_NAME CLK_100M_PCH_SLOTX24_S2_DP
J 0
(3020 1960);
DISPLAY 0.617021 (3020 1960);
PAINT ORANGE (3020 1960);
WIRE 16 -1 (3650 1800)(1525 1800);
FORCEPROP 0 LAST SIG_NAME CLK_100M_PCH_SLOTX24_S1_DN
J 0
(3020 1810);
DISPLAY 0.617021 (3020 1810);
PAINT ORANGE (3020 1810);
WIRE 16 -1 (3650 1700)(1525 1700);
FORCEPROP 0 LAST SIG_NAME CLK_100M_PCH_SLOTX24_S0_DN
J 0
(3020 1710);
DISPLAY 0.617021 (3020 1710);
PAINT ORANGE (3020 1710);
WIRE 16 -1 (3650 1600)(1525 1600);
FORCEPROP 0 LAST SIG_NAME CLK_100M_DB1200_DN
J 0
(3020 1610);
DISPLAY 0.617021 (3020 1610);
PAINT ORANGE (3020 1610);
WIRE 16 -1 (3650 1500)(1525 1500);
FORCEPROP 0 LAST SIG_NAME CLK_100M_AIRMAX8_PE1_DN
J 0
(3020 1510);
DISPLAY 0.617021 (3020 1510);
PAINT ORANGE (3020 1510);
WIRE 16 -1 (3650 2050)(1525 2050);
FORCEPROP 0 LAST SIG_NAME CLK_100M_PCH_SLOTX24_S3_DP
J 0
(3020 2060);
DISPLAY 0.617021 (3020 2060);
PAINT ORANGE (3020 2060);
WIRE 16 -1 (1525 1400)(3650 1400);
FORCEPROP 2 LAST SIG_NAME TP_CLK_24M_PMSYNC2
J 0
(3015 1410);
DISPLAY 0.617021 (3015 1410);
PAINT ORANGE (3015 1410);
FORCEPROP 2 LASTPROP $XRERR UNIQUE?
J 0
(3680 1400);
DISPLAY 0.638298 (3680 1400);
PAINT MONO (3680 1400);
DISPLAY INVISIBLE (3680 1400);
WIRE 16 -1 (-475 1350)(-2300 1350);
FORCEPROP 0 LAST SIG_NAME XTAL_PCH_48M_OUT
J 0
(-2300 1351);
DISPLAY 0.617021 (-2300 1351);
PAINT ORANGE (-2300 1351);
WIRE 16 -1 (-475 1700)(-2300 1700);
FORCEPROP 0 LAST SIG_NAME XTAL_PCH_48M_IN
J 0
(-2300 1701);
DISPLAY 0.617021 (-2300 1701);
PAINT ORANGE (-2300 1701);
WIRE 16 -1 (1525 1350)(2200 1350);
FORCEPROP 2 LAST SIG_NAME H_PMSYNC_CLK_24M_R
J 0
(1665 1360);
DISPLAY 0.617021 (1665 1360);
PAINT ORANGE (1665 1360);
FORCEPROP 2 LASTPROP $XRERR UNIQUE?
J 0
(1425 1360);
DISPLAY 0.638298 (1425 1360);
PAINT MONO (1425 1360);
DISPLAY INVISIBLE (1425 1360);
WIRE 16 -1 (3650 550)(1850 550);
WIRE 16 -1 (1850 1300)(1850 550);
WIRE 16 -1 (1850 1300)(1525 1300);
WIRE 16 -1 (-2300 2800)(-1375 2800);
FORCEPROP 2 LAST SIG_NAME CLK_100M_BMC_PE_R_DN
J 0
(-2300 2810);
DISPLAY 0.617021 (-2300 2810);
PAINT ORANGE (-2300 2810);
WIRE 16 -1 (-2300 2850)(-1725 2850);
FORCEPROP 2 LAST SIG_NAME CLK_100M_BMC_PE_R_DP
J 0
(-2300 2860);
DISPLAY 0.617021 (-2300 2860);
PAINT ORANGE (-2300 2860);
WIRE 16 -1 (-475 1900)(-2300 1900);
FORCEPROP 0 LAST SIG_NAME XTAL_33K_RTC2
J 0
(-2300 1910);
DISPLAY 0.617021 (-2300 1910);
PAINT ORANGE (-2300 1910);
WIRE 16 -1 (-475 2650)(-2300 2650);
FORCEPROP 0 LAST SIG_NAME TP_CLK_100M_PLAT1_DP
J 0
(-2300 2660);
DISPLAY 0.617021 (-2300 2660);
PAINT ORANGE (-2300 2660);
FORCEPROP 2 LASTPROP $XRERR UNIQUE?
J 0
(-2540 2650);
DISPLAY 0.638298 (-2540 2650);
PAINT MONO (-2540 2650);
DISPLAY INVISIBLE (-2540 2650);
WIRE 16 -1 (-475 2750)(-2300 2750);
FORCEPROP 0 LAST SIG_NAME TP_CLK_100M_NSSCC0_DP
J 0
(-2300 2760);
DISPLAY 0.617021 (-2300 2760);
PAINT ORANGE (-2300 2760);
FORCEPROP 2 LASTPROP $XRERR UNIQUE?
J 0
(-2540 2750);
DISPLAY 0.638298 (-2540 2750);
PAINT MONO (-2540 2750);
DISPLAY INVISIBLE (-2540 2750);
WIRE 16 -1 (-1525 2850)(-475 2850);
FORCEPROP 2 LAST SIG_NAME CLK_100M_BMC_PE_DP
J 0
(-1060 2860);
DISPLAY 0.617021 (-1060 2860);
PAINT ORANGE (-1060 2860);
FORCEPROP 2 LASTPROP $XRERR UNIQUE?
J 0
(-1300 2860);
DISPLAY 0.638298 (-1300 2860);
PAINT MONO (-1300 2860);
DISPLAY INVISIBLE (-1300 2860);
WIRE 16 -1 (-2850 2950)(-2850 2850);
WIRE 16 -1 (-2850 2950)(-475 2950);
FORCEPROP 0 LAST SIG_NAME A_PCH_XCLK_BIASREF
J 0
(-2725 2951);
DISPLAY 0.617021 (-2725 2951);
PAINT ORANGE (-2725 2951);
FORCEPROP 2 LASTPROP $XRERR UNIQUE?
J 0
(-2965 2951);
DISPLAY 0.638298 (-2965 2951);
PAINT MONO (-2965 2951);
DISPLAY INVISIBLE (-2965 2951);
WIRE 16 -1 (-3150 2950)(-3150 2850);
WIRE 16 -1 (-3150 2950)(-2850 2950);
WIRE 16 -1 (-2025 -100)(-2025 150);
WIRE 16 -1 (-2025 150)(-1875 150);
WIRE 16 -1 (-2025 150)(-2025 475);
WIRE 16 -1 (-2025 475)(-1875 475);
WIRE 16 -1 (-2025 625)(-2525 625);
FORCEPROP 2 LAST SIG_NAME XTAL_PCH_48M_IN
J 0
(-2460 635);
DISPLAY 0.617021 (-2460 635);
PAINT ORANGE (-2460 635);
WIRE 16 -1 (-2025 625)(-2025 475);
WIRE 16 -1 (-275 -125)(-275 125);
WIRE 16 -1 (-275 125)(-125 125);
WIRE 16 -1 (-275 125)(-275 475);
WIRE 16 -1 (-275 475)(-125 475);
WIRE 16 -1 (-275 625)(-275 475);
WIRE 16 -1 (-875 625)(-275 625);
FORCEPROP 2 LAST SIG_NAME XTAL_33K_RTC1
J 0
(-785 635);
DISPLAY 0.617021 (-785 635);
PAINT ORANGE (-785 635);
WIRE 16 -1 (225 -125)(225 125);
WIRE 16 -1 (225 125)(75 125);
WIRE 16 -1 (225 125)(225 475);
WIRE 16 -1 (75 475)(225 475);
WIRE 16 -1 (225 725)(-875 725);
FORCEPROP 2 LAST SIG_NAME XTAL_33K_RTC2
J 0
(-785 735);
DISPLAY 0.617021 (-785 735);
PAINT ORANGE (-785 735);
WIRE 16 -1 (225 725)(225 475);
WIRE 3 682 (-350 -50)(-350 -600);
WIRE 3 682 (550 -50)(-350 -50);
WIRE 3 682 (-350 -600)(550 -600);
WIRE 3 682 (550 -600)(550 -50);
WIRE 16 -1 (-1525 -100)(-1525 150);
WIRE 16 -1 (-1675 150)(-1525 150);
WIRE 16 -1 (-1525 725)(-2525 725);
WIRE 16 -1 (-1675 475)(-1525 475);
WIRE 16 -1 (-1525 150)(-1525 475);
WIRE 16 -1 (-1525 475)(-1525 725);
FORCEPROP 2 LAST SIG_NAME XTAL_PCH_48M_OUT
J 0
(-2460 735);
DISPLAY 0.617021 (-2460 735);
PAINT ORANGE (-2460 735);
WIRE 3 682 (-1000 -650)(-2100 -650);
WIRE 3 682 (-1000 50)(-1000 -650);
WIRE 3 682 (-2100 -650)(-2100 50);
WIRE 3 682 (-2100 50)(-1000 50);
WIRE 16 -1 (-1675 3050)(-475 3050);
FORCEPROP 2 LAST SIG_NAME TP_PCH_RSVD65
J 0
(-1685 3060);
DISPLAY 0.617021 (-1685 3060);
PAINT ORANGE (-1685 3060);
FORCEPROP 2 LASTPROP $XRERR UNIQUE?
J 0
(-1915 3050);
DISPLAY 0.638298 (-1915 3050);
PAINT MONO (-1915 3050);
DISPLAY INVISIBLE (-1915 3050);
WIRE 16 -1 (-2300 2500)(-475 2500);
FORCEPROP 0 LAST SIG_NAME TP_CLK_100M_NSSCC1_DN
J 0
(-2300 2510);
DISPLAY 0.617021 (-2300 2510);
PAINT ORANGE (-2300 2510);
FORCEPROP 2 LASTPROP $XRERR UNIQUE?
J 0
(-2540 2500);
DISPLAY 0.638298 (-2540 2500);
PAINT MONO (-2540 2500);
DISPLAY INVISIBLE (-2540 2500);
WIRE 16 -1 (-475 2600)(-2300 2600);
FORCEPROP 0 LAST SIG_NAME TP_CLK_100M_PLAT1_DN
J 0
(-2300 2610);
DISPLAY 0.617021 (-2300 2610);
PAINT ORANGE (-2300 2610);
FORCEPROP 2 LASTPROP $XRERR UNIQUE?
J 0
(-2540 2600);
DISPLAY 0.638298 (-2540 2600);
PAINT MONO (-2540 2600);
DISPLAY INVISIBLE (-2540 2600);
WIRE 16 -1 (-475 2700)(-2300 2700);
FORCEPROP 0 LAST SIG_NAME TP_CLK_100M_NSSCC0_DN
J 0
(-2300 2710);
DISPLAY 0.617021 (-2300 2710);
PAINT ORANGE (-2300 2710);
FORCEPROP 2 LASTPROP $XRERR UNIQUE?
J 0
(-2540 2700);
DISPLAY 0.638298 (-2540 2700);
PAINT MONO (-2540 2700);
DISPLAY INVISIBLE (-2540 2700);
WIRE 16 -1 (-1175 2800)(-475 2800);
FORCEPROP 2 LAST SIG_NAME CLK_100M_BMC_PE_DN
J 0
(-1060 2810);
DISPLAY 0.617021 (-1060 2810);
PAINT ORANGE (-1060 2810);
FORCEPROP 2 LASTPROP $XRERR UNIQUE?
J 0
(-1300 2810);
DISPLAY 0.638298 (-1300 2810);
PAINT MONO (-1300 2810);
DISPLAY INVISIBLE (-1300 2810);
WIRE 16 -1 (-1675 3000)(-475 3000);
FORCEPROP 2 LAST SIG_NAME TP_PCH_RSVD64
J 0
(-1685 3010);
DISPLAY 0.617021 (-1685 3010);
PAINT ORANGE (-1685 3010);
FORCEPROP 2 LASTPROP $XRERR UNIQUE?
J 0
(-1915 3000);
DISPLAY 0.638298 (-1915 3000);
PAINT MONO (-1915 3000);
DISPLAY INVISIBLE (-1915 3000);
WIRE 3 2175 (-1800 2725)(-1125 2725);
WIRE 3 2175 (-1125 3200)(-1125 2725);
WIRE 3 2175 (-1800 3200)(-1800 2725);
WIRE 3 2175 (-1800 3200)(-1125 3200);
WIRE 16 -1 (-2300 2550)(-475 2550);
FORCEPROP 0 LAST SIG_NAME TP_CLK_100M_NSSCC1_DP
J 0
(-2300 2560);
DISPLAY 0.617021 (-2300 2560);
PAINT ORANGE (-2300 2560);
FORCEPROP 2 LASTPROP $XRERR UNIQUE?
J 0
(-2540 2550);
DISPLAY 0.638298 (-2540 2550);
PAINT MONO (-2540 2550);
DISPLAY INVISIBLE (-2540 2550);
WIRE 16 -1 (-2300 2400)(-475 2400);
FORCEPROP 0 LAST SIG_NAME CLK_100M_PCH_XDP_DN
J 0
(-2300 2401);
DISPLAY 0.617021 (-2300 2401);
PAINT ORANGE (-2300 2401);
WIRE 16 -1 (-2300 2300)(-475 2300);
FORCEPROP 0 LAST SIG_NAME XTAL_33K_RTC1
J 0
(-2300 2310);
DISPLAY 0.617021 (-2300 2310);
PAINT ORANGE (-2300 2310);
DOT 1 (225 475);
DOT 1 (2900 1350);
DOT 1 (-275 125);
DOT 1 (-1525 475);
DOT 1 (-2025 475);
DOT 1 (-275 -475);
DOT 1 (-275 475);
DOT 1 (-2850 2950);
DOT 1 (-2025 -500);
DOT 1 (-1525 150);
DOT 1 (-2025 150);
DOT 1 (225 125);
DOT 1 (1700 2700);
FORCENOTE
TP FAB3 CHANGE CAPS TO 6.8PF 0815
(-2100 -700) 0;
DISPLAY LEFT (-2100 -700);
DISPLAY 0.638298 (-2100 -700);
PAINT RED (-2100 -700);
FORCENOTE
TP FAB1 ADD CAP C3W1 0121
(-2925 2150) 0;
DISPLAY LEFT (-2925 2150);
DISPLAY 1.021277 (-2925 2150);
PAINT RED (-2925 2150);
FORCENOTE
ROOM=SB
(-3000 -750) 0;
DISPLAY LEFT (-3000 -750);
DISPLAY 0.808511 (-3000 -750);
PAINT PURPLE (-3000 -750);
FORCENOTE
TP FAB3 CHANGE CAP 0826
(-350 -650) 0;
DISPLAY LEFT (-350 -650);
DISPLAY 1.021277 (-350 -650);
PAINT RED (-350 -650);
FORCENOTE
POP RES R7C4 AND R7C2 WHEN USE BMC AST2500 0106
(-1800 3425) 0;
DISPLAY LEFT (-1800 3425);
DISPLAY 1.021277 (-1800 3425);
PAINT RED (-1800 3425);
FORCENOTE
TP FAB4 DISCONNECT 20170111
(1750 2700) 0;
DISPLAY LEFT (1750 2700);
DISPLAY 0.638298 (1750 2700);
PAINT RED (1750 2700);
QUIT
